FILE_TYPE = MACRO_DRAWING;
SET COLOR_WIRE YELLOW;
SET COLOR_PROP ORANGE;
SET COLOR_DOT WHITE;
SET COLOR_ARC YELLOW;
SET COLOR_BODY GREEN;
SET COLOR_NOTE PURPLE;
SET PROP_DISPLAY VALUE;
SET PAGE_NUMBER P376;
FORCEADD UNIVERSAL_GND..1
(-5750 5325);
FORCEPROP 3 LASTPIN (-5750 5375) SIG_NAME GND\g
J 0
(-5740 5385);
DISPLAY 0.659574 (-5740 5385);
PAINT MONO (-5740 5385);
DISPLAY INVISIBLE (-5740 5385);
FORCEPROP 2 LAST CDS_LIB pure_quanta_power
J 0
(-5750 5325);
DISPLAY INVISIBLE (-5750 5325);
FORCEPROP 1 LAST HDL_POWER GND
J 1
(-5725 5250);
DISPLAY 0.872340 (-5725 5250);
PAINT GREEN (-5725 5250);
DISPLAY INVISIBLE (-5725 5250);
FORCEPROP 1 LAST PATH I10
J 0
(-5675 5325);
DISPLAY 0.872340 (-5675 5325);
PAINT AQUA (-5675 5325);
DISPLAY INVISIBLE (-5675 5325);
FORCEADD UNIVERSAL_POWER..1
(-1350 2825);
FORCEPROP 3 LASTPIN (-1350 2775) SIG_NAME P3V3_AUX\g
J 0
(-1340 2785);
DISPLAY 0.659574 (-1340 2785);
PAINT MONO (-1340 2785);
DISPLAY INVISIBLE (-1340 2785);
FORCEPROP 1 LAST HDL_POWER P3V3_AUX
J 1
(-1350 2875);
DISPLAY 0.489362 (-1350 2875);
PAINT GREEN (-1350 2875);
FORCEPROP 2 LAST CDS_LIB pure_quanta_power
J 0
(-1350 2825);
DISPLAY INVISIBLE (-1350 2825);
FORCEPROP 1 LAST PATH I100
J 0
(-1300 2850);
DISPLAY 0.872340 (-1300 2850);
PAINT AQUA (-1300 2850);
DISPLAY INVISIBLE (-1300 2850);
FORCEADD OFFPAGE..3
(-650 725);
FORCEPROP 2 LAST $XR1 301 
J 0
(-316 725);
DISPLAY 0.638298 (-316 725);
PAINT MONO (-316 725);
FORCEPROP 2 LAST $XR0 185 
J 0
(-436 725);
DISPLAY 0.638298 (-436 725);
PAINT MONO (-436 725);
FORCEPROP 2 LAST CDS_LIB standard
J 2
(-650 725);
DISPLAY INVISIBLE (-650 725);
FORCEPROP 1 LAST OFFPAGE TRUE
J 0
(-325 600);
DISPLAY 0.872340 (-325 600);
PAINT GREEN (-325 600);
DISPLAY INVISIBLE (-325 600);
FORCEPROP 1 LAST COMMENT_BODY TRUE
J 0
(-700 625);
DISPLAY 0.872340 (-700 625);
PAINT GREEN (-700 625);
DISPLAY INVISIBLE (-700 625);
FORCEPROP 2 LAST PATH I101
J 0
(-450 800);
DISPLAY 0.680851 (-450 800);
DISPLAY INVISIBLE (-450 800);
FORCEADD OFFPAGE..2
(-650 775);
FORCEPROP 2 LAST $XR1 301 
J 0
(-341 775);
DISPLAY 0.638298 (-341 775);
PAINT MONO (-341 775);
FORCEPROP 2 LAST $XR0 185 
J 0
(-461 775);
DISPLAY 0.638298 (-461 775);
PAINT MONO (-461 775);
FORCEPROP 2 LAST CDS_LIB standard
J 2
(-650 775);
DISPLAY INVISIBLE (-650 775);
FORCEPROP 1 LAST OFFPAGE TRUE
J 0
(-325 650);
DISPLAY 0.872340 (-325 650);
PAINT GREEN (-325 650);
DISPLAY INVISIBLE (-325 650);
FORCEPROP 1 LAST COMMENT_BODY TRUE
J 0
(-695 680);
DISPLAY 0.872340 (-695 680);
PAINT GREEN (-695 680);
DISPLAY INVISIBLE (-695 680);
FORCEPROP 2 LAST PATH I102
J 0
(-475 850);
DISPLAY 0.680851 (-475 850);
DISPLAY INVISIBLE (-475 850);
FORCEADD UNIVERSAL_POWER..1
(-1325 1400);
FORCEPROP 3 LASTPIN (-1325 1350) SIG_NAME P3V3_AUX\g
J 0
(-1315 1360);
DISPLAY 0.659574 (-1315 1360);
PAINT MONO (-1315 1360);
DISPLAY INVISIBLE (-1315 1360);
FORCEPROP 1 LAST HDL_POWER P3V3_AUX
J 1
(-1325 1450);
DISPLAY 0.489362 (-1325 1450);
PAINT GREEN (-1325 1450);
FORCEPROP 2 LAST CDS_LIB pure_quanta_power
J 0
(-1325 1400);
DISPLAY INVISIBLE (-1325 1400);
FORCEPROP 1 LAST PATH I103
J 0
(-1275 1425);
DISPLAY 0.872340 (-1275 1425);
PAINT AQUA (-1275 1425);
DISPLAY INVISIBLE (-1275 1425);
FORCEADD UNIVERSAL_GND..1
(-1500 1800);
FORCEPROP 3 LASTPIN (-1500 1850) SIG_NAME GND\g
J 0
(-1490 1860);
DISPLAY 0.659574 (-1490 1860);
PAINT MONO (-1490 1860);
DISPLAY INVISIBLE (-1490 1860);
FORCEPROP 2 LAST CDS_LIB pure_quanta_power
J 0
(-1500 1800);
DISPLAY INVISIBLE (-1500 1800);
FORCEPROP 1 LAST HDL_POWER GND
J 1
(-1475 1725);
DISPLAY 0.872340 (-1475 1725);
PAINT GREEN (-1475 1725);
DISPLAY INVISIBLE (-1475 1725);
FORCEPROP 1 LAST PATH I104
J 0
(-1425 1800);
DISPLAY 0.872340 (-1425 1800);
PAINT AQUA (-1425 1800);
DISPLAY INVISIBLE (-1425 1800);
FORCEADD Q_CAP..1
(-1175 1125);
FORCEPROP 1 LAST LOCATION C1071
J 0
(-1125 1225);
DISPLAY 0.808511 (-1125 1225);
FORCEPROP 0 LAST $SEC 1
J 0
(-1125 1275);
DISPLAY 0.680851 (-1125 1275);
PAINT MONO (-1125 1275);
DISPLAY INVISIBLE (-1125 1275);
FORCEPROP 0 LAST CDS_SEC 1
J 0
(-1125 1275);
DISPLAY 0.680851 (-1125 1275);
DISPLAY INVISIBLE (-1125 1275);
FORCEPROP 1 LASTPIN (-1175 1225) $PN 1
J 0
(-1165 1205);
DISPLAY 0.787234 (-1165 1205);
PAINT MONO (-1165 1205);
FORCEPROP 1 LASTPIN (-1175 1025) $PN 2
J 0
(-1165 1005);
DISPLAY 0.787234 (-1165 1005);
PAINT MONO (-1165 1005);
FORCEPROP 1 LAST VALUE 0.1UF
J 0
(-1125 1175);
DISPLAY 0.638298 (-1125 1175);
FORCEPROP 1 LAST VOLTAGE 10V
J 0
(-1125 1125);
DISPLAY 0.638298 (-1125 1125);
FORCEPROP 1 LAST PACK_TYPE C0201
J 0
(-1125 925);
DISPLAY 0.638298 (-1125 925);
FORCEPROP 1 LAST TOLERANCE 10%
J 0
(-1125 1075);
DISPLAY 0.638298 (-1125 1075);
FORCEPROP 1 LAST MATERIAL X7S
J 0
(-1125 1025);
DISPLAY 0.638298 (-1125 1025);
FORCEPROP 2 LAST CDS_LIB pure_quanta
J 0
(-1175 1125);
DISPLAY INVISIBLE (-1175 1125);
FORCEPROP 1 LAST PATH I105
J 0
(-1125 1275);
DISPLAY 0.978723 (-1125 1275);
PAINT WHITE (-1125 1275);
DISPLAY INVISIBLE (-1125 1275);
FORCEPROP 1 LAST PART_NUMBER CH4102K6E00
J 0
(-1125 975);
DISPLAY 0.638298 (-1125 975);
DISPLAY INVISIBLE (-1125 975);
FORCEADD UNIVERSAL_GND..1
(-1175 925);
FORCEPROP 3 LASTPIN (-1175 975) SIG_NAME GND\g
J 0
(-1165 985);
DISPLAY 0.659574 (-1165 985);
PAINT MONO (-1165 985);
DISPLAY INVISIBLE (-1165 985);
FORCEPROP 2 LAST CDS_LIB pure_quanta_power
J 0
(-1175 925);
DISPLAY INVISIBLE (-1175 925);
FORCEPROP 1 LAST HDL_POWER GND
J 1
(-1150 850);
DISPLAY 0.872340 (-1150 850);
PAINT GREEN (-1150 850);
DISPLAY INVISIBLE (-1150 850);
FORCEPROP 1 LAST PATH I106
J 0
(-1100 925);
DISPLAY 0.872340 (-1100 925);
PAINT AQUA (-1100 925);
DISPLAY INVISIBLE (-1100 925);
FORCEADD UNIVERSAL_GND..1
(-1475 375);
FORCEPROP 3 LASTPIN (-1475 425) SIG_NAME GND\g
J 0
(-1465 435);
DISPLAY 0.659574 (-1465 435);
PAINT MONO (-1465 435);
DISPLAY INVISIBLE (-1465 435);
FORCEPROP 2 LAST CDS_LIB pure_quanta_power
J 0
(-1475 375);
DISPLAY INVISIBLE (-1475 375);
FORCEPROP 1 LAST HDL_POWER GND
J 1
(-1450 300);
DISPLAY 0.872340 (-1450 300);
PAINT GREEN (-1450 300);
DISPLAY INVISIBLE (-1450 300);
FORCEPROP 1 LAST PATH I107
J 0
(-1400 375);
DISPLAY 0.872340 (-1400 375);
PAINT AQUA (-1400 375);
DISPLAY INVISIBLE (-1400 375);
FORCEADD PI3CSW12ZUAEX..1
(-1900 2100);
FORCEPROP 1 LAST LOCATION U46
J 0
(-2044 2593);
DISPLAY 0.723404 (-2044 2593);
PAINT GREEN (-2044 2593);
FORCEPROP 0 LAST $SEC 1
J 0
(-2025 2750);
DISPLAY 0.680851 (-2025 2750);
PAINT MONO (-2025 2750);
DISPLAY INVISIBLE (-2025 2750);
FORCEPROP 0 LAST CDS_SEC 1
J 0
(-2025 2750);
DISPLAY 0.680851 (-2025 2750);
DISPLAY INVISIBLE (-2025 2750);
FORCEPROP 0 LASTPIN (-2200 2100) $PN 1
J 2
(-2210 2110);
DISPLAY 0.680851 (-2210 2110);
PAINT MONO (-2210 2110);
FORCEPROP 0 LASTPIN (-2200 2050) $PN 2
J 2
(-2210 2060);
DISPLAY 0.680851 (-2210 2060);
PAINT MONO (-2210 2060);
FORCEPROP 0 LASTPIN (-2200 2000) $PN 3
J 2
(-2210 2010);
DISPLAY 0.680851 (-2210 2010);
PAINT MONO (-2210 2010);
FORCEPROP 0 LASTPIN (-2200 1950) $PN 4
J 2
(-2210 1960);
DISPLAY 0.680851 (-2210 1960);
PAINT MONO (-2210 1960);
FORCEPROP 0 LASTPIN (-1600 2200) $PN 8
J 0
(-1590 2210);
DISPLAY 0.680851 (-1590 2210);
PAINT MONO (-1590 2210);
FORCEPROP 0 LASTPIN (-1600 2150) $PN 7
J 0
(-1590 2160);
DISPLAY 0.680851 (-1590 2160);
PAINT MONO (-1590 2160);
FORCEPROP 0 LASTPIN (-1600 1950) $PN 5
J 0
(-1590 1960);
DISPLAY 0.680851 (-1590 1960);
PAINT MONO (-1590 1960);
FORCEPROP 0 LASTPIN (-2200 2250) $PN 6
J 2
(-2210 2260);
DISPLAY 0.680851 (-2210 2260);
PAINT MONO (-2210 2260);
FORCEPROP 0 LASTPIN (-2200 2200) $PN 9
J 2
(-2210 2210);
DISPLAY 0.680851 (-2210 2210);
PAINT MONO (-2210 2210);
FORCEPROP 0 LASTPIN (-1600 2250) $PN 10
J 0
(-1590 2260);
DISPLAY 0.680851 (-1590 2260);
PAINT MONO (-1590 2260);
FORCEPROP 1 LAST MATERIAL IC
J 0
(-2044 2319);
DISPLAY 0.723404 (-2044 2319);
PAINT GREEN (-2044 2319);
FORCEPROP 2 LAST VALUE PI3CSW12ZUAEX
J 0
(-2025 2650);
DISPLAY 0.680851 (-2025 2650);
FORCEPROP 2 LAST PART_TYPE SMLF
J 0
(-2025 2700);
DISPLAY 0.680851 (-2025 2700);
FORCEPROP 2 LAST CDS_LIB pure_quanta
J 2
(-1900 2100);
DISPLAY INVISIBLE (-1900 2100);
FORCEPROP 1 LAST CDS_LMAN_SYM_OUTLINE -150,200,150,-200
J 0
(-1900 2100);
DISPLAY 0.468085 (-1900 2100);
PAINT GREEN (-1900 2100);
DISPLAY INVISIBLE (-1900 2100);
FORCEPROP 1 LAST NEEDS_NO_SIZE TRUE
J 0
(-1900 2100);
DISPLAY 0.723404 (-1900 2100);
PAINT GREEN (-1900 2100);
DISPLAY INVISIBLE (-1900 2100);
FORCEPROP 1 LAST PATH I108
J 0
(-1900 2100);
DISPLAY 0.723404 (-1900 2100);
PAINT GREEN (-1900 2100);
DISPLAY INVISIBLE (-1900 2100);
FORCEPROP 1 LAST PART_NUMBER AL3CSW12000
J 0
(-2044 2446);
DISPLAY 0.723404 (-2044 2446);
PAINT GREEN (-2044 2446);
DISPLAY INVISIBLE (-2044 2446);
FORCEADD Q_RES..1
(-3100 3675);
FORCEPROP 1 LAST LOCATION R1210
J 0
(-2950 3675);
DISPLAY 0.638298 (-2950 3675);
PAINT SKYBLUE (-2950 3675);
FORCEPROP 0 LAST $SEC 1
J 0
(-2950 3725);
DISPLAY 0.680851 (-2950 3725);
PAINT MONO (-2950 3725);
DISPLAY INVISIBLE (-2950 3725);
FORCEPROP 0 LAST CDS_SEC 1
J 0
(-2950 3725);
DISPLAY 0.680851 (-2950 3725);
DISPLAY INVISIBLE (-2950 3725);
FORCEPROP 1 LASTPIN (-3200 3675) $PN 1
J 0
(-3188 3687);
DISPLAY 0.787234 (-3188 3687);
PAINT MONO (-3188 3687);
FORCEPROP 1 LASTPIN (-3000 3675) $PN 2
J 0
(-3038 3687);
DISPLAY 0.787234 (-3038 3687);
PAINT MONO (-3038 3687);
FORCEPROP 1 LAST VALUE 0
J 2
(-3225 3675);
DISPLAY 0.510638 (-3225 3675);
FORCEPROP 1 LAST PACK_TYPE 0201LF
J 0
(-3525 3675);
DISPLAY 0.510638 (-3525 3675);
FORCEPROP 1 LAST MATERIAL CHIP
J 0
(-3375 3675);
DISPLAY 0.510638 (-3375 3675);
FORCEPROP 1 LAST TOLERANCE 5%
J 0
(-3325 3675);
DISPLAY 0.510638 (-3325 3675);
DISPLAY INVISIBLE (-3325 3675);
FORCEPROP 1 LAST WATTAGE 1/20W
J 2
(-3300 3750);
DISPLAY 0.510638 (-3300 3750);
DISPLAY INVISIBLE (-3300 3750);
FORCEPROP 2 LAST CDS_LIB pure_quanta
J 0
(-3100 3675);
DISPLAY INVISIBLE (-3100 3675);
FORCEPROP 1 LAST PATH I109
J 0
(-3150 3825);
DISPLAY 0.978723 (-3150 3825);
PAINT WHITE (-3150 3825);
DISPLAY INVISIBLE (-3150 3825);
FORCEPROP 1 LAST PART_NUMBER CS00001JE10
J 0
(-3150 3800);
DISPLAY 0.510638 (-3150 3800);
DISPLAY INVISIBLE (-3150 3800);
FORCEADD Q_RES..1
(-3100 3725);
FORCEPROP 1 LAST LOCATION R1218
J 0
(-2950 3725);
DISPLAY 0.787234 (-2950 3725);
PAINT SKYBLUE (-2950 3725);
FORCEPROP 0 LAST $SEC 1
J 0
(-2950 3775);
DISPLAY 0.680851 (-2950 3775);
PAINT MONO (-2950 3775);
DISPLAY INVISIBLE (-2950 3775);
FORCEPROP 0 LAST CDS_SEC 1
J 0
(-2950 3775);
DISPLAY 0.680851 (-2950 3775);
DISPLAY INVISIBLE (-2950 3775);
FORCEPROP 1 LASTPIN (-3200 3725) $PN 1
J 0
(-3188 3737);
DISPLAY 0.787234 (-3188 3737);
PAINT MONO (-3188 3737);
FORCEPROP 1 LASTPIN (-3000 3725) $PN 2
J 0
(-3038 3737);
DISPLAY 0.787234 (-3038 3737);
PAINT MONO (-3038 3737);
FORCEPROP 1 LAST VALUE 1K
J 2
(-3200 3725);
DISPLAY 0.638298 (-3200 3725);
FORCEPROP 1 LAST PACK_TYPE 0201LF
J 0
(-3600 3725);
DISPLAY 0.638298 (-3600 3725);
FORCEPROP 1 LAST MATERIAL CHIP
J 0
(-3400 3725);
DISPLAY 0.638298 (-3400 3725);
FORCEPROP 2 LAST CDS_LIB pure_quanta
J 0
(-3100 3725);
DISPLAY INVISIBLE (-3100 3725);
FORCEPROP 1 LAST TOLERANCE 1%
J 0
(-3125 3925);
DISPLAY 0.978723 (-3125 3925);
DISPLAY INVISIBLE (-3125 3925);
FORCEPROP 1 LAST WATTAGE 1/20W
J 2
(-2725 3925);
DISPLAY 0.978723 (-2725 3925);
DISPLAY INVISIBLE (-2725 3925);
FORCEPROP 1 LAST PATH I110
J 0
(-3150 3875);
DISPLAY 0.978723 (-3150 3875);
PAINT WHITE (-3150 3875);
DISPLAY INVISIBLE (-3150 3875);
FORCEPROP 1 LAST PART_NUMBER CS21001FE07
J 0
(-3150 3825);
DISPLAY 0.978723 (-3150 3825);
DISPLAY INVISIBLE (-3150 3825);
FORCEADD OFFPAGE..1
(-3225 3575);
FORCEPROP 2 LASTPIN (-3175 3575) SIG_NAME SMB_RT_CPU0_P1_ROM_MUX_1D_SCL
J 0
(-3160 3585);
DISPLAY 0.680851 (-3160 3585);
FORCEPROP 2 LAST $XR1 288 
J 0
(-3597 3575);
DISPLAY 0.638298 (-3597 3575);
PAINT MONO (-3597 3575);
FORCEPROP 2 LAST $XR0 185 
J 0
(-3477 3575);
DISPLAY 0.638298 (-3477 3575);
PAINT MONO (-3477 3575);
FORCEPROP 2 LAST CDS_LIB standard
J 2
(-3225 3575);
DISPLAY INVISIBLE (-3225 3575);
FORCEPROP 1 LAST OFFPAGE TRUE
J 0
(-2900 3450);
DISPLAY 1.170213 (-2900 3450);
PAINT GREEN (-2900 3450);
DISPLAY INVISIBLE (-2900 3450);
FORCEPROP 1 LAST COMMENT_BODY TRUE
J 0
(-3100 3475);
DISPLAY 1.170213 (-3100 3475);
PAINT GREEN (-3100 3475);
DISPLAY INVISIBLE (-3100 3475);
FORCEPROP 2 LAST PATH I111
J 0
(-3175 3650);
DISPLAY 0.680851 (-3175 3650);
DISPLAY INVISIBLE (-3175 3650);
FORCEADD OFFPAGE..1
(-3225 3475);
FORCEPROP 2 LAST $XR0 185 
J 0
(-3537 3475);
DISPLAY 0.638298 (-3537 3475);
PAINT MONO (-3537 3475);
FORCEPROP 2 LAST CDS_LIB standard
J 0
(-3225 3475);
DISPLAY INVISIBLE (-3225 3475);
FORCEPROP 1 LAST OFFPAGE TRUE
J 0
(-2900 3350);
DISPLAY 1.170213 (-2900 3350);
PAINT GREEN (-2900 3350);
DISPLAY INVISIBLE (-2900 3350);
FORCEPROP 1 LAST COMMENT_BODY TRUE
J 0
(-3100 3375);
DISPLAY 1.170213 (-3100 3375);
PAINT GREEN (-3100 3375);
DISPLAY INVISIBLE (-3100 3375);
FORCEPROP 2 LAST PATH I112
J 0
(-3175 3550);
DISPLAY 0.680851 (-3175 3550);
DISPLAY INVISIBLE (-3175 3550);
FORCEADD OFFPAGE..3
R 2
(-3225 3425);
FORCEPROP 2 LAST $XR0 185 
J 0
(-3535 3425);
DISPLAY 0.638298 (-3535 3425);
PAINT MONO (-3535 3425);
FORCEPROP 2 LAST CDS_LIB standard
J 2
(-3225 3425);
DISPLAY INVISIBLE (-3225 3425);
FORCEPROP 1 LAST OFFPAGE TRUE
J 2
(-3550 3300);
DISPLAY 0.872340 (-3550 3300);
PAINT GREEN (-3550 3300);
DISPLAY INVISIBLE (-3550 3300);
FORCEPROP 1 LAST COMMENT_BODY TRUE
J 2
(-3175 3325);
DISPLAY 0.872340 (-3175 3325);
PAINT GREEN (-3175 3325);
DISPLAY INVISIBLE (-3175 3325);
FORCEPROP 2 LAST PATH I113
J 0
(-3175 3500);
DISPLAY 0.680851 (-3175 3500);
DISPLAY INVISIBLE (-3175 3500);
FORCEADD OFFPAGE..3
R 2
(-3225 3525);
FORCEPROP 2 LAST $XR1 288 
J 0
(-3655 3525);
DISPLAY 0.638298 (-3655 3525);
PAINT MONO (-3655 3525);
FORCEPROP 2 LAST $XR0 185 
J 0
(-3535 3525);
DISPLAY 0.638298 (-3535 3525);
PAINT MONO (-3535 3525);
FORCEPROP 2 LAST CDS_LIB standard
J 0
(-3225 3525);
DISPLAY INVISIBLE (-3225 3525);
FORCEPROP 1 LAST OFFPAGE TRUE
J 2
(-3550 3400);
DISPLAY 0.872340 (-3550 3400);
PAINT GREEN (-3550 3400);
DISPLAY INVISIBLE (-3550 3400);
FORCEPROP 1 LAST COMMENT_BODY TRUE
J 2
(-3175 3425);
DISPLAY 0.872340 (-3175 3425);
PAINT GREEN (-3175 3425);
DISPLAY INVISIBLE (-3175 3425);
FORCEPROP 2 LAST PATH I114
J 0
(-3175 3600);
DISPLAY 0.680851 (-3175 3600);
DISPLAY INVISIBLE (-3175 3600);
FORCEADD Q_RES..1
(-3150 2200);
FORCEPROP 1 LAST LOCATION R1206
J 0
(-3000 2200);
DISPLAY 0.638298 (-3000 2200);
PAINT SKYBLUE (-3000 2200);
FORCEPROP 0 LAST $SEC 1
J 0
(-3000 2250);
DISPLAY 0.680851 (-3000 2250);
PAINT MONO (-3000 2250);
DISPLAY INVISIBLE (-3000 2250);
FORCEPROP 0 LAST CDS_SEC 1
J 0
(-3000 2250);
DISPLAY 0.680851 (-3000 2250);
DISPLAY INVISIBLE (-3000 2250);
FORCEPROP 1 LASTPIN (-3250 2200) $PN 1
J 0
(-3238 2212);
DISPLAY 0.787234 (-3238 2212);
PAINT MONO (-3238 2212);
FORCEPROP 1 LASTPIN (-3050 2200) $PN 2
J 0
(-3088 2212);
DISPLAY 0.787234 (-3088 2212);
PAINT MONO (-3088 2212);
FORCEPROP 1 LAST PACK_TYPE 0201LF
J 0
(-3575 2200);
DISPLAY 0.510638 (-3575 2200);
FORCEPROP 1 LAST MATERIAL CHIP
J 0
(-3425 2200);
DISPLAY 0.510638 (-3425 2200);
FORCEPROP 1 LAST VALUE 0
J 2
(-3275 2200);
DISPLAY 0.510638 (-3275 2200);
FORCEPROP 1 LAST TOLERANCE 5%
J 0
(-3375 2200);
DISPLAY 0.510638 (-3375 2200);
DISPLAY INVISIBLE (-3375 2200);
FORCEPROP 1 LAST WATTAGE 1/20W
J 2
(-3350 2275);
DISPLAY 0.510638 (-3350 2275);
DISPLAY INVISIBLE (-3350 2275);
FORCEPROP 2 LAST CDS_LIB pure_quanta
J 0
(-3150 2200);
DISPLAY INVISIBLE (-3150 2200);
FORCEPROP 1 LAST PATH I115
J 0
(-3200 2350);
DISPLAY 0.978723 (-3200 2350);
PAINT WHITE (-3200 2350);
DISPLAY INVISIBLE (-3200 2350);
FORCEPROP 1 LAST PART_NUMBER CS00001JE10
J 0
(-3200 2325);
DISPLAY 0.510638 (-3200 2325);
DISPLAY INVISIBLE (-3200 2325);
FORCEADD Q_RES..1
(-3150 2250);
FORCEPROP 1 LAST LOCATION R1216
J 0
(-3000 2250);
DISPLAY 0.787234 (-3000 2250);
PAINT SKYBLUE (-3000 2250);
FORCEPROP 0 LAST $SEC 1
J 0
(-3000 2300);
DISPLAY 0.680851 (-3000 2300);
PAINT MONO (-3000 2300);
DISPLAY INVISIBLE (-3000 2300);
FORCEPROP 0 LAST CDS_SEC 1
J 0
(-3000 2300);
DISPLAY 0.680851 (-3000 2300);
DISPLAY INVISIBLE (-3000 2300);
FORCEPROP 1 LASTPIN (-3250 2250) $PN 1
J 0
(-3238 2262);
DISPLAY 0.787234 (-3238 2262);
PAINT MONO (-3238 2262);
FORCEPROP 1 LASTPIN (-3050 2250) $PN 2
J 0
(-3088 2262);
DISPLAY 0.787234 (-3088 2262);
PAINT MONO (-3088 2262);
FORCEPROP 1 LAST PACK_TYPE 0201LF
J 0
(-3650 2250);
DISPLAY 0.638298 (-3650 2250);
FORCEPROP 1 LAST MATERIAL CHIP
J 0
(-3450 2250);
DISPLAY 0.638298 (-3450 2250);
FORCEPROP 1 LAST VALUE 1K
J 2
(-3250 2250);
DISPLAY 0.638298 (-3250 2250);
FORCEPROP 2 LAST CDS_LIB pure_quanta
J 0
(-3150 2250);
DISPLAY INVISIBLE (-3150 2250);
FORCEPROP 1 LAST TOLERANCE 1%
J 0
(-3175 2450);
DISPLAY 0.978723 (-3175 2450);
DISPLAY INVISIBLE (-3175 2450);
FORCEPROP 1 LAST WATTAGE 1/20W
J 2
(-2775 2450);
DISPLAY 0.978723 (-2775 2450);
DISPLAY INVISIBLE (-2775 2450);
FORCEPROP 1 LAST PATH I116
J 0
(-3200 2400);
DISPLAY 0.978723 (-3200 2400);
PAINT WHITE (-3200 2400);
DISPLAY INVISIBLE (-3200 2400);
FORCEPROP 1 LAST PART_NUMBER CS21001FE07
J 0
(-3200 2350);
DISPLAY 0.978723 (-3200 2350);
DISPLAY INVISIBLE (-3200 2350);
FORCEADD OFFPAGE..1
(-3275 2100);
FORCEPROP 2 LASTPIN (-3225 2100) SIG_NAME SMB_RT_CPU0_P3_ROM_MUX_1D_SCL
J 0
(-3210 2110);
DISPLAY 0.680851 (-3210 2110);
FORCEPROP 2 LAST $XR1 310 
J 0
(-3647 2100);
DISPLAY 0.638298 (-3647 2100);
PAINT MONO (-3647 2100);
FORCEPROP 2 LAST $XR0 185 
J 0
(-3527 2100);
DISPLAY 0.638298 (-3527 2100);
PAINT MONO (-3527 2100);
FORCEPROP 2 LAST CDS_LIB standard
J 2
(-3275 2100);
DISPLAY INVISIBLE (-3275 2100);
FORCEPROP 1 LAST OFFPAGE TRUE
J 0
(-2950 1975);
DISPLAY 1.170213 (-2950 1975);
PAINT GREEN (-2950 1975);
DISPLAY INVISIBLE (-2950 1975);
FORCEPROP 1 LAST COMMENT_BODY TRUE
J 0
(-3150 2000);
DISPLAY 1.170213 (-3150 2000);
PAINT GREEN (-3150 2000);
DISPLAY INVISIBLE (-3150 2000);
FORCEPROP 2 LAST PATH I117
J 0
(-3225 2175);
DISPLAY 0.680851 (-3225 2175);
DISPLAY INVISIBLE (-3225 2175);
FORCEADD OFFPAGE..3
R 2
(-3275 2050);
FORCEPROP 2 LAST $XR1 310 
J 0
(-3675 2050);
DISPLAY 0.638298 (-3675 2050);
PAINT MONO (-3675 2050);
FORCEPROP 2 LAST $XR0 185 
J 0
(-3555 2050);
DISPLAY 0.638298 (-3555 2050);
PAINT MONO (-3555 2050);
FORCEPROP 2 LAST CDS_LIB standard
J 0
(-3275 2050);
DISPLAY INVISIBLE (-3275 2050);
FORCEPROP 1 LAST OFFPAGE TRUE
J 2
(-3600 1925);
DISPLAY 0.872340 (-3600 1925);
PAINT GREEN (-3600 1925);
DISPLAY INVISIBLE (-3600 1925);
FORCEPROP 1 LAST COMMENT_BODY TRUE
J 2
(-3225 1950);
DISPLAY 0.872340 (-3225 1950);
PAINT GREEN (-3225 1950);
DISPLAY INVISIBLE (-3225 1950);
FORCEPROP 2 LAST PATH I118
J 0
(-3225 2125);
DISPLAY 0.680851 (-3225 2125);
DISPLAY INVISIBLE (-3225 2125);
FORCEADD OFFPAGE..1
(-3275 2000);
FORCEPROP 2 LAST $XR0 185 
J 0
(-3557 2000);
DISPLAY 0.638298 (-3557 2000);
PAINT MONO (-3557 2000);
FORCEPROP 2 LAST CDS_LIB standard
J 0
(-3275 2000);
DISPLAY INVISIBLE (-3275 2000);
FORCEPROP 1 LAST OFFPAGE TRUE
J 0
(-2950 1875);
DISPLAY 1.170213 (-2950 1875);
PAINT GREEN (-2950 1875);
DISPLAY INVISIBLE (-2950 1875);
FORCEPROP 1 LAST COMMENT_BODY TRUE
J 0
(-3150 1900);
DISPLAY 1.170213 (-3150 1900);
PAINT GREEN (-3150 1900);
DISPLAY INVISIBLE (-3150 1900);
FORCEPROP 2 LAST PATH I119
J 0
(-3225 2075);
DISPLAY 0.680851 (-3225 2075);
DISPLAY INVISIBLE (-3225 2075);
FORCEADD OFFPAGE..3
R 2
(-3275 1950);
FORCEPROP 2 LAST $XR0 185 
J 0
(-3555 1950);
DISPLAY 0.638298 (-3555 1950);
PAINT MONO (-3555 1950);
FORCEPROP 2 LAST CDS_LIB standard
J 2
(-3275 1950);
DISPLAY INVISIBLE (-3275 1950);
FORCEPROP 1 LAST OFFPAGE TRUE
J 2
(-3600 1825);
DISPLAY 0.872340 (-3600 1825);
PAINT GREEN (-3600 1825);
DISPLAY INVISIBLE (-3600 1825);
FORCEPROP 1 LAST COMMENT_BODY TRUE
J 2
(-3225 1850);
DISPLAY 0.872340 (-3225 1850);
PAINT GREEN (-3225 1850);
DISPLAY INVISIBLE (-3225 1850);
FORCEPROP 2 LAST PATH I120
J 0
(-3225 2025);
DISPLAY 0.680851 (-3225 2025);
DISPLAY INVISIBLE (-3225 2025);
FORCEADD PI3CSW12ZUAEX..1
(-1875 675);
FORCEPROP 1 LAST LOCATION U47
J 0
(-2019 1168);
DISPLAY 0.723404 (-2019 1168);
PAINT GREEN (-2019 1168);
FORCEPROP 0 LAST $SEC 1
J 0
(-2000 1325);
DISPLAY 0.680851 (-2000 1325);
PAINT MONO (-2000 1325);
DISPLAY INVISIBLE (-2000 1325);
FORCEPROP 0 LAST CDS_SEC 1
J 0
(-2000 1325);
DISPLAY 0.680851 (-2000 1325);
DISPLAY INVISIBLE (-2000 1325);
FORCEPROP 0 LASTPIN (-2175 675) $PN 1
J 2
(-2185 685);
DISPLAY 0.680851 (-2185 685);
PAINT MONO (-2185 685);
FORCEPROP 0 LASTPIN (-2175 625) $PN 2
J 2
(-2185 635);
DISPLAY 0.680851 (-2185 635);
PAINT MONO (-2185 635);
FORCEPROP 0 LASTPIN (-2175 575) $PN 3
J 2
(-2185 585);
DISPLAY 0.680851 (-2185 585);
PAINT MONO (-2185 585);
FORCEPROP 0 LASTPIN (-2175 525) $PN 4
J 2
(-2185 535);
DISPLAY 0.680851 (-2185 535);
PAINT MONO (-2185 535);
FORCEPROP 0 LASTPIN (-1575 775) $PN 8
J 0
(-1565 785);
DISPLAY 0.680851 (-1565 785);
PAINT MONO (-1565 785);
FORCEPROP 0 LASTPIN (-1575 725) $PN 7
J 0
(-1565 735);
DISPLAY 0.680851 (-1565 735);
PAINT MONO (-1565 735);
FORCEPROP 0 LASTPIN (-1575 525) $PN 5
J 0
(-1565 535);
DISPLAY 0.680851 (-1565 535);
PAINT MONO (-1565 535);
FORCEPROP 0 LASTPIN (-2175 825) $PN 6
J 2
(-2185 835);
DISPLAY 0.680851 (-2185 835);
PAINT MONO (-2185 835);
FORCEPROP 0 LASTPIN (-2175 775) $PN 9
J 2
(-2185 785);
DISPLAY 0.680851 (-2185 785);
PAINT MONO (-2185 785);
FORCEPROP 0 LASTPIN (-1575 825) $PN 10
J 0
(-1565 835);
DISPLAY 0.680851 (-1565 835);
PAINT MONO (-1565 835);
FORCEPROP 1 LAST MATERIAL IC
J 0
(-2019 894);
DISPLAY 0.723404 (-2019 894);
PAINT GREEN (-2019 894);
FORCEPROP 2 LAST PART_TYPE SMLF
J 0
(-2000 1275);
DISPLAY 0.680851 (-2000 1275);
FORCEPROP 2 LAST VALUE PI3CSW12ZUAEX
J 0
(-2000 1225);
DISPLAY 0.680851 (-2000 1225);
FORCEPROP 1 LAST NEEDS_NO_SIZE TRUE
J 0
(-1875 675);
DISPLAY 0.723404 (-1875 675);
PAINT GREEN (-1875 675);
DISPLAY INVISIBLE (-1875 675);
FORCEPROP 1 LAST CDS_LMAN_SYM_OUTLINE -150,200,150,-200
J 0
(-1875 675);
DISPLAY 0.468085 (-1875 675);
PAINT GREEN (-1875 675);
DISPLAY INVISIBLE (-1875 675);
FORCEPROP 2 LAST CDS_LIB pure_quanta
J 2
(-1875 675);
DISPLAY INVISIBLE (-1875 675);
FORCEPROP 1 LAST PATH I121
J 0
(-1875 675);
DISPLAY 0.723404 (-1875 675);
PAINT GREEN (-1875 675);
DISPLAY INVISIBLE (-1875 675);
FORCEPROP 1 LAST PART_NUMBER AL3CSW12000
J 0
(-2019 1021);
DISPLAY 0.723404 (-2019 1021);
PAINT GREEN (-2019 1021);
DISPLAY INVISIBLE (-2019 1021);
FORCEADD Q_RES..1
(-3125 825);
FORCEPROP 1 LAST LOCATION R1217
J 0
(-2975 825);
DISPLAY 0.787234 (-2975 825);
PAINT SKYBLUE (-2975 825);
FORCEPROP 0 LAST $SEC 1
J 0
(-2975 875);
DISPLAY 0.680851 (-2975 875);
PAINT MONO (-2975 875);
DISPLAY INVISIBLE (-2975 875);
FORCEPROP 0 LAST CDS_SEC 1
J 0
(-2975 875);
DISPLAY 0.680851 (-2975 875);
DISPLAY INVISIBLE (-2975 875);
FORCEPROP 1 LASTPIN (-3225 825) $PN 1
J 0
(-3213 837);
DISPLAY 0.787234 (-3213 837);
PAINT MONO (-3213 837);
FORCEPROP 1 LASTPIN (-3025 825) $PN 2
J 0
(-3063 837);
DISPLAY 0.787234 (-3063 837);
PAINT MONO (-3063 837);
FORCEPROP 1 LAST PACK_TYPE 0201LF
J 0
(-3625 825);
DISPLAY 0.638298 (-3625 825);
FORCEPROP 1 LAST MATERIAL CHIP
J 0
(-3425 825);
DISPLAY 0.638298 (-3425 825);
FORCEPROP 1 LAST VALUE 1K
J 2
(-3225 825);
DISPLAY 0.638298 (-3225 825);
FORCEPROP 2 LAST CDS_LIB pure_quanta
J 0
(-3125 825);
DISPLAY INVISIBLE (-3125 825);
FORCEPROP 1 LAST TOLERANCE 1%
J 0
(-3150 1025);
DISPLAY 0.978723 (-3150 1025);
DISPLAY INVISIBLE (-3150 1025);
FORCEPROP 1 LAST WATTAGE 1/20W
J 2
(-2750 1025);
DISPLAY 0.978723 (-2750 1025);
DISPLAY INVISIBLE (-2750 1025);
FORCEPROP 1 LAST PATH I122
J 0
(-3175 975);
DISPLAY 0.978723 (-3175 975);
PAINT WHITE (-3175 975);
DISPLAY INVISIBLE (-3175 975);
FORCEPROP 1 LAST PART_NUMBER CS21001FE07
J 0
(-3175 925);
DISPLAY 0.978723 (-3175 925);
DISPLAY INVISIBLE (-3175 925);
FORCEADD Q_RES..1
(-3125 775);
FORCEPROP 1 LAST LOCATION R1209
J 0
(-2975 775);
DISPLAY 0.638298 (-2975 775);
PAINT SKYBLUE (-2975 775);
FORCEPROP 0 LAST $SEC 1
J 0
(-2975 825);
DISPLAY 0.680851 (-2975 825);
PAINT MONO (-2975 825);
DISPLAY INVISIBLE (-2975 825);
FORCEPROP 0 LAST CDS_SEC 1
J 0
(-2975 825);
DISPLAY 0.680851 (-2975 825);
DISPLAY INVISIBLE (-2975 825);
FORCEPROP 1 LASTPIN (-3225 775) $PN 1
J 0
(-3213 787);
DISPLAY 0.787234 (-3213 787);
PAINT MONO (-3213 787);
FORCEPROP 1 LASTPIN (-3025 775) $PN 2
J 0
(-3063 787);
DISPLAY 0.787234 (-3063 787);
PAINT MONO (-3063 787);
FORCEPROP 1 LAST VALUE 0
J 2
(-3250 775);
DISPLAY 0.510638 (-3250 775);
FORCEPROP 1 LAST MATERIAL CHIP
J 0
(-3400 775);
DISPLAY 0.510638 (-3400 775);
FORCEPROP 1 LAST PACK_TYPE 0201LF
J 0
(-3550 775);
DISPLAY 0.510638 (-3550 775);
FORCEPROP 2 LAST CDS_LIB pure_quanta
J 0
(-3125 775);
DISPLAY INVISIBLE (-3125 775);
FORCEPROP 1 LAST WATTAGE 1/20W
J 2
(-3325 850);
DISPLAY 0.510638 (-3325 850);
DISPLAY INVISIBLE (-3325 850);
FORCEPROP 1 LAST TOLERANCE 5%
J 0
(-3350 775);
DISPLAY 0.510638 (-3350 775);
DISPLAY INVISIBLE (-3350 775);
FORCEPROP 1 LAST PATH I123
J 0
(-3175 925);
DISPLAY 0.978723 (-3175 925);
PAINT WHITE (-3175 925);
DISPLAY INVISIBLE (-3175 925);
FORCEPROP 1 LAST PART_NUMBER CS00001JE10
J 0
(-3175 900);
DISPLAY 0.510638 (-3175 900);
DISPLAY INVISIBLE (-3175 900);
FORCEADD OFFPAGE..1
(-3250 675);
FORCEPROP 2 LASTPIN (-3200 675) SIG_NAME SMB_RT_CPU0_P2_ROM_MUX_1D_SCL
J 0
(-3185 685);
DISPLAY 0.680851 (-3185 685);
FORCEPROP 2 LAST $XR1 299 
J 0
(-3622 675);
DISPLAY 0.638298 (-3622 675);
PAINT MONO (-3622 675);
FORCEPROP 2 LAST $XR0 185 
J 0
(-3502 675);
DISPLAY 0.638298 (-3502 675);
PAINT MONO (-3502 675);
FORCEPROP 2 LAST CDS_LIB standard
J 2
(-3250 675);
DISPLAY INVISIBLE (-3250 675);
FORCEPROP 1 LAST OFFPAGE TRUE
J 0
(-2925 550);
DISPLAY 1.170213 (-2925 550);
PAINT GREEN (-2925 550);
DISPLAY INVISIBLE (-2925 550);
FORCEPROP 1 LAST COMMENT_BODY TRUE
J 0
(-3125 575);
DISPLAY 1.170213 (-3125 575);
PAINT GREEN (-3125 575);
DISPLAY INVISIBLE (-3125 575);
FORCEPROP 2 LAST PATH I124
J 0
(-3200 750);
DISPLAY 0.680851 (-3200 750);
DISPLAY INVISIBLE (-3200 750);
FORCEADD OFFPAGE..3
R 2
(-3250 625);
FORCEPROP 2 LAST $XR1 299 
J 0
(-3650 625);
DISPLAY 0.638298 (-3650 625);
PAINT MONO (-3650 625);
FORCEPROP 2 LAST $XR0 185 
J 0
(-3530 625);
DISPLAY 0.638298 (-3530 625);
PAINT MONO (-3530 625);
FORCEPROP 2 LAST CDS_LIB standard
J 0
(-3250 625);
DISPLAY INVISIBLE (-3250 625);
FORCEPROP 1 LAST OFFPAGE TRUE
J 2
(-3575 500);
DISPLAY 0.872340 (-3575 500);
PAINT GREEN (-3575 500);
DISPLAY INVISIBLE (-3575 500);
FORCEPROP 1 LAST COMMENT_BODY TRUE
J 2
(-3200 525);
DISPLAY 0.872340 (-3200 525);
PAINT GREEN (-3200 525);
DISPLAY INVISIBLE (-3200 525);
FORCEPROP 2 LAST PATH I125
J 0
(-3200 700);
DISPLAY 0.680851 (-3200 700);
DISPLAY INVISIBLE (-3200 700);
FORCEADD OFFPAGE..1
(-3250 575);
FORCEPROP 2 LAST $XR0 185 
J 0
(-3532 575);
DISPLAY 0.638298 (-3532 575);
PAINT MONO (-3532 575);
FORCEPROP 2 LAST CDS_LIB standard
J 0
(-3250 575);
DISPLAY INVISIBLE (-3250 575);
FORCEPROP 1 LAST OFFPAGE TRUE
J 0
(-2925 450);
DISPLAY 1.170213 (-2925 450);
PAINT GREEN (-2925 450);
DISPLAY INVISIBLE (-2925 450);
FORCEPROP 1 LAST COMMENT_BODY TRUE
J 0
(-3125 475);
DISPLAY 1.170213 (-3125 475);
PAINT GREEN (-3125 475);
DISPLAY INVISIBLE (-3125 475);
FORCEPROP 2 LAST PATH I126
J 0
(-3200 650);
DISPLAY 0.680851 (-3200 650);
DISPLAY INVISIBLE (-3200 650);
FORCEADD OFFPAGE..3
R 2
(-3250 525);
FORCEPROP 2 LAST $XR0 185 
J 0
(-3530 525);
DISPLAY 0.638298 (-3530 525);
PAINT MONO (-3530 525);
FORCEPROP 2 LAST CDS_LIB standard
J 2
(-3250 525);
DISPLAY INVISIBLE (-3250 525);
FORCEPROP 1 LAST OFFPAGE TRUE
J 2
(-3575 400);
DISPLAY 0.872340 (-3575 400);
PAINT GREEN (-3575 400);
DISPLAY INVISIBLE (-3575 400);
FORCEPROP 1 LAST COMMENT_BODY TRUE
J 2
(-3200 425);
DISPLAY 0.872340 (-3200 425);
PAINT GREEN (-3200 425);
DISPLAY INVISIBLE (-3200 425);
FORCEPROP 2 LAST PATH I127
J 0
(-3200 600);
DISPLAY 0.680851 (-3200 600);
DISPLAY INVISIBLE (-3200 600);
FORCEADD UNIVERSAL_GND..1
R 5
(-4225 5250);
FORCEPROP 3 LASTPIN (-4175 5250) SIG_NAME GND\g
J 0
(-4165 5260);
DISPLAY 0.659574 (-4165 5260);
PAINT MONO (-4165 5260);
DISPLAY INVISIBLE (-4165 5260);
FORCEPROP 2 LAST CDS_LIB pure_quanta_power
R 3
J 0
(-4225 5250);
DISPLAY INVISIBLE (-4225 5250);
FORCEPROP 1 LAST HDL_POWER GND
R 3
J 1
(-4300 5225);
DISPLAY 0.872340 (-4300 5225);
PAINT GREEN (-4300 5225);
DISPLAY INVISIBLE (-4300 5225);
FORCEPROP 1 LAST PATH I128
R 3
J 0
(-4225 5175);
DISPLAY 0.872340 (-4225 5175);
PAINT AQUA (-4225 5175);
DISPLAY INVISIBLE (-4225 5175);
FORCEADD OFFPAGE..1
(-4325 5200);
FORCEPROP 2 LAST $XR2 186 
J 0
(-4816 5200);
DISPLAY 0.638298 (-4816 5200);
PAINT MONO (-4816 5200);
FORCEPROP 2 LAST $XR1 185 
J 0
(-4696 5200);
DISPLAY 0.638298 (-4696 5200);
PAINT MONO (-4696 5200);
FORCEPROP 2 LAST $XR0 81 
J 0
(-4576 5200);
DISPLAY 0.638298 (-4576 5200);
PAINT MONO (-4576 5200);
FORCEPROP 2 LAST CDS_LIB standard
J 0
(-4325 5200);
DISPLAY INVISIBLE (-4325 5200);
FORCEPROP 1 LAST OFFPAGE TRUE
J 0
(-4000 5075);
DISPLAY 1.170213 (-4000 5075);
PAINT GREEN (-4000 5075);
DISPLAY INVISIBLE (-4000 5075);
FORCEPROP 1 LAST COMMENT_BODY TRUE
J 0
(-4200 5100);
DISPLAY 1.170213 (-4200 5100);
PAINT GREEN (-4200 5100);
DISPLAY INVISIBLE (-4200 5100);
FORCEPROP 2 LAST PATH I129
J 0
(-4275 5275);
DISPLAY 0.680851 (-4275 5275);
DISPLAY INVISIBLE (-4275 5275);
FORCEADD OFFPAGE..1
(-8700 5725);
FORCEPROP 2 LAST $XR2 186 
J 0
(-9191 5725);
DISPLAY 0.638298 (-9191 5725);
PAINT MONO (-9191 5725);
FORCEPROP 2 LAST $XR1 185 
J 0
(-9071 5725);
DISPLAY 0.638298 (-9071 5725);
PAINT MONO (-9071 5725);
FORCEPROP 2 LAST $XR0 81 
J 0
(-8951 5725);
DISPLAY 0.638298 (-8951 5725);
PAINT MONO (-8951 5725);
FORCEPROP 2 LAST CDS_LIB standard
J 0
(-8700 5725);
DISPLAY INVISIBLE (-8700 5725);
FORCEPROP 1 LAST OFFPAGE TRUE
J 0
(-8375 5600);
DISPLAY 1.170213 (-8375 5600);
PAINT GREEN (-8375 5600);
DISPLAY INVISIBLE (-8375 5600);
FORCEPROP 1 LAST COMMENT_BODY TRUE
J 0
(-8575 5625);
DISPLAY 1.170213 (-8575 5625);
PAINT GREEN (-8575 5625);
DISPLAY INVISIBLE (-8575 5625);
FORCEPROP 2 LAST PATH I13
J 0
(-8650 5800);
DISPLAY 0.680851 (-8650 5800);
DISPLAY INVISIBLE (-8650 5800);
FORCEADD UNIVERSAL_GND..1
R 5
(-4300 3725);
FORCEPROP 3 LASTPIN (-4250 3725) SIG_NAME GND\g
J 0
(-4240 3735);
DISPLAY 0.659574 (-4240 3735);
PAINT MONO (-4240 3735);
DISPLAY INVISIBLE (-4240 3735);
FORCEPROP 2 LAST CDS_LIB pure_quanta_power
R 3
J 0
(-4300 3725);
DISPLAY INVISIBLE (-4300 3725);
FORCEPROP 1 LAST HDL_POWER GND
R 3
J 1
(-4375 3700);
DISPLAY 0.872340 (-4375 3700);
PAINT GREEN (-4375 3700);
DISPLAY INVISIBLE (-4375 3700);
FORCEPROP 1 LAST PATH I130
R 3
J 0
(-4300 3650);
DISPLAY 0.872340 (-4300 3650);
PAINT AQUA (-4300 3650);
DISPLAY INVISIBLE (-4300 3650);
FORCEADD OFFPAGE..1
(-4400 3675);
FORCEPROP 2 LAST $XR2 186 
J 0
(-4861 3675);
DISPLAY 0.638298 (-4861 3675);
PAINT MONO (-4861 3675);
FORCEPROP 2 LAST $XR1 185 
J 0
(-4741 3675);
DISPLAY 0.638298 (-4741 3675);
PAINT MONO (-4741 3675);
FORCEPROP 2 LAST $XR0 81 
J 0
(-4621 3675);
DISPLAY 0.638298 (-4621 3675);
PAINT MONO (-4621 3675);
FORCEPROP 2 LAST CDS_LIB standard
J 0
(-4400 3675);
DISPLAY INVISIBLE (-4400 3675);
FORCEPROP 1 LAST OFFPAGE TRUE
J 0
(-4075 3550);
DISPLAY 1.170213 (-4075 3550);
PAINT GREEN (-4075 3550);
DISPLAY INVISIBLE (-4075 3550);
FORCEPROP 1 LAST COMMENT_BODY TRUE
J 0
(-4275 3575);
DISPLAY 1.170213 (-4275 3575);
PAINT GREEN (-4275 3575);
DISPLAY INVISIBLE (-4275 3575);
FORCEPROP 2 LAST PATH I131
J 0
(-4350 3750);
DISPLAY 0.680851 (-4350 3750);
DISPLAY INVISIBLE (-4350 3750);
FORCEADD UNIVERSAL_GND..1
R 5
(-4350 2250);
FORCEPROP 3 LASTPIN (-4300 2250) SIG_NAME GND\g
J 0
(-4290 2260);
DISPLAY 0.659574 (-4290 2260);
PAINT MONO (-4290 2260);
DISPLAY INVISIBLE (-4290 2260);
FORCEPROP 2 LAST CDS_LIB pure_quanta_power
R 3
J 0
(-4350 2250);
DISPLAY INVISIBLE (-4350 2250);
FORCEPROP 1 LAST HDL_POWER GND
R 3
J 1
(-4425 2225);
DISPLAY 0.872340 (-4425 2225);
PAINT GREEN (-4425 2225);
DISPLAY INVISIBLE (-4425 2225);
FORCEPROP 1 LAST PATH I132
R 3
J 0
(-4350 2175);
DISPLAY 0.872340 (-4350 2175);
PAINT AQUA (-4350 2175);
DISPLAY INVISIBLE (-4350 2175);
FORCEADD OFFPAGE..1
(-4450 2200);
FORCEPROP 2 LAST $XR2 186 
J 0
(-4941 2200);
DISPLAY 0.638298 (-4941 2200);
PAINT MONO (-4941 2200);
FORCEPROP 2 LAST $XR1 185 
J 0
(-4821 2200);
DISPLAY 0.638298 (-4821 2200);
PAINT MONO (-4821 2200);
FORCEPROP 2 LAST $XR0 81 
J 0
(-4701 2200);
DISPLAY 0.638298 (-4701 2200);
PAINT MONO (-4701 2200);
FORCEPROP 2 LAST CDS_LIB standard
J 0
(-4450 2200);
DISPLAY INVISIBLE (-4450 2200);
FORCEPROP 1 LAST OFFPAGE TRUE
J 0
(-4125 2075);
DISPLAY 1.170213 (-4125 2075);
PAINT GREEN (-4125 2075);
DISPLAY INVISIBLE (-4125 2075);
FORCEPROP 1 LAST COMMENT_BODY TRUE
J 0
(-4325 2100);
DISPLAY 1.170213 (-4325 2100);
PAINT GREEN (-4325 2100);
DISPLAY INVISIBLE (-4325 2100);
FORCEPROP 2 LAST PATH I133
J 0
(-4400 2275);
DISPLAY 0.680851 (-4400 2275);
DISPLAY INVISIBLE (-4400 2275);
FORCEADD UNIVERSAL_GND..1
R 5
(-4325 825);
FORCEPROP 3 LASTPIN (-4275 825) SIG_NAME GND\g
J 0
(-4265 835);
DISPLAY 0.659574 (-4265 835);
PAINT MONO (-4265 835);
DISPLAY INVISIBLE (-4265 835);
FORCEPROP 2 LAST CDS_LIB pure_quanta_power
R 3
J 0
(-4325 825);
DISPLAY INVISIBLE (-4325 825);
FORCEPROP 1 LAST HDL_POWER GND
R 3
J 1
(-4400 800);
DISPLAY 0.872340 (-4400 800);
PAINT GREEN (-4400 800);
DISPLAY INVISIBLE (-4400 800);
FORCEPROP 1 LAST PATH I134
R 3
J 0
(-4325 750);
DISPLAY 0.872340 (-4325 750);
PAINT AQUA (-4325 750);
DISPLAY INVISIBLE (-4325 750);
FORCEADD OFFPAGE..1
(-4425 775);
FORCEPROP 2 LAST $XR2 186 
J 0
(-4916 775);
DISPLAY 0.638298 (-4916 775);
PAINT MONO (-4916 775);
FORCEPROP 2 LAST $XR1 185 
J 0
(-4796 775);
DISPLAY 0.638298 (-4796 775);
PAINT MONO (-4796 775);
FORCEPROP 2 LAST $XR0 81 
J 0
(-4676 775);
DISPLAY 0.638298 (-4676 775);
PAINT MONO (-4676 775);
FORCEPROP 2 LAST CDS_LIB standard
J 0
(-4425 775);
DISPLAY INVISIBLE (-4425 775);
FORCEPROP 1 LAST OFFPAGE TRUE
J 0
(-4100 650);
DISPLAY 1.170213 (-4100 650);
PAINT GREEN (-4100 650);
DISPLAY INVISIBLE (-4100 650);
FORCEPROP 1 LAST COMMENT_BODY TRUE
J 0
(-4300 675);
DISPLAY 1.170213 (-4300 675);
PAINT GREEN (-4300 675);
DISPLAY INVISIBLE (-4300 675);
FORCEPROP 2 LAST PATH I135
J 0
(-4375 850);
DISPLAY 0.680851 (-4375 850);
DISPLAY INVISIBLE (-4375 850);
FORCEADD OFFPAGE..2
(-4925 5725);
FORCEPROP 2 LAST $XR1 323 
J 0
(-4616 5725);
DISPLAY 0.638298 (-4616 5725);
PAINT MONO (-4616 5725);
FORCEPROP 2 LAST $XR0 185 
J 0
(-4736 5725);
DISPLAY 0.638298 (-4736 5725);
PAINT MONO (-4736 5725);
FORCEPROP 2 LAST CDS_LIB standard
J 2
(-4925 5725);
DISPLAY INVISIBLE (-4925 5725);
FORCEPROP 1 LAST OFFPAGE TRUE
J 0
(-4600 5600);
DISPLAY 0.872340 (-4600 5600);
PAINT GREEN (-4600 5600);
DISPLAY INVISIBLE (-4600 5600);
FORCEPROP 1 LAST COMMENT_BODY TRUE
J 0
(-4970 5630);
DISPLAY 0.872340 (-4970 5630);
PAINT GREEN (-4970 5630);
DISPLAY INVISIBLE (-4970 5630);
FORCEPROP 2 LAST PATH I16
J 2
(-4975 5800);
DISPLAY 0.680851 (-4975 5800);
DISPLAY INVISIBLE (-4975 5800);
FORCEADD OFFPAGE..3
(-4925 5675);
FORCEPROP 2 LAST $XR1 323 
J 0
(-4591 5675);
DISPLAY 0.638298 (-4591 5675);
PAINT MONO (-4591 5675);
FORCEPROP 2 LAST $XR0 185 
J 0
(-4711 5675);
DISPLAY 0.638298 (-4711 5675);
PAINT MONO (-4711 5675);
FORCEPROP 2 LAST CDS_LIB standard
J 2
(-4925 5675);
DISPLAY INVISIBLE (-4925 5675);
FORCEPROP 1 LAST OFFPAGE TRUE
J 0
(-4600 5550);
DISPLAY 0.872340 (-4600 5550);
PAINT GREEN (-4600 5550);
DISPLAY INVISIBLE (-4600 5550);
FORCEPROP 1 LAST COMMENT_BODY TRUE
J 0
(-4975 5575);
DISPLAY 0.872340 (-4975 5575);
PAINT GREEN (-4975 5575);
DISPLAY INVISIBLE (-4975 5575);
FORCEPROP 2 LAST PATH I17
J 2
(-4975 5750);
DISPLAY 0.680851 (-4975 5750);
DISPLAY INVISIBLE (-4975 5750);
FORCEADD OFFPAGE..3
R 2
(-7525 5475);
FORCEPROP 2 LAST $XR0 185 
J 0
(-7805 5475);
DISPLAY 0.638298 (-7805 5475);
PAINT MONO (-7805 5475);
FORCEPROP 2 LAST CDS_LIB standard
J 2
(-7525 5475);
DISPLAY INVISIBLE (-7525 5475);
FORCEPROP 1 LAST OFFPAGE TRUE
J 2
(-7850 5350);
DISPLAY 0.872340 (-7850 5350);
PAINT GREEN (-7850 5350);
DISPLAY INVISIBLE (-7850 5350);
FORCEPROP 1 LAST COMMENT_BODY TRUE
J 2
(-7475 5375);
DISPLAY 0.872340 (-7475 5375);
PAINT GREEN (-7475 5375);
DISPLAY INVISIBLE (-7475 5375);
FORCEPROP 2 LAST PATH I19
J 2
(-7725 5550);
DISPLAY 0.680851 (-7725 5550);
DISPLAY INVISIBLE (-7725 5550);
FORCEADD OFFPAGE..1
(-7525 5625);
FORCEPROP 2 LASTPIN (-7475 5625) SIG_NAME SMB_RT_CPU1_P0_ROM_MUX_1D_SCL
J 0
(-7460 5635);
DISPLAY 0.680851 (-7460 5635);
FORCEPROP 2 LAST $XR1 321 
J 0
(-7897 5625);
DISPLAY 0.638298 (-7897 5625);
PAINT MONO (-7897 5625);
FORCEPROP 2 LAST $XR0 185 
J 0
(-7777 5625);
DISPLAY 0.638298 (-7777 5625);
PAINT MONO (-7777 5625);
FORCEPROP 2 LAST CDS_LIB standard
J 2
(-7525 5625);
DISPLAY INVISIBLE (-7525 5625);
FORCEPROP 1 LAST OFFPAGE TRUE
J 0
(-7200 5500);
DISPLAY 1.170213 (-7200 5500);
PAINT GREEN (-7200 5500);
DISPLAY INVISIBLE (-7200 5500);
FORCEPROP 1 LAST COMMENT_BODY TRUE
J 0
(-7400 5525);
DISPLAY 1.170213 (-7400 5525);
PAINT GREEN (-7400 5525);
DISPLAY INVISIBLE (-7400 5525);
FORCEPROP 2 LAST PATH I20
J 2
(-7700 5700);
DISPLAY 0.680851 (-7700 5700);
DISPLAY INVISIBLE (-7700 5700);
FORCEADD PI3CSW12ZUAEX..1
(-6150 5625);
FORCEPROP 1 LAST LOCATION U45
J 0
(-6294 6118);
DISPLAY 0.723404 (-6294 6118);
PAINT GREEN (-6294 6118);
FORCEPROP 0 LAST $SEC 1
J 0
(-6275 6275);
DISPLAY 0.680851 (-6275 6275);
PAINT MONO (-6275 6275);
DISPLAY INVISIBLE (-6275 6275);
FORCEPROP 0 LAST CDS_SEC 1
J 0
(-6275 6275);
DISPLAY 0.680851 (-6275 6275);
DISPLAY INVISIBLE (-6275 6275);
FORCEPROP 0 LASTPIN (-6450 5625) $PN 1
J 2
(-6460 5635);
DISPLAY 0.680851 (-6460 5635);
PAINT MONO (-6460 5635);
FORCEPROP 0 LASTPIN (-6450 5575) $PN 2
J 2
(-6460 5585);
DISPLAY 0.680851 (-6460 5585);
PAINT MONO (-6460 5585);
FORCEPROP 0 LASTPIN (-6450 5525) $PN 3
J 2
(-6460 5535);
DISPLAY 0.680851 (-6460 5535);
PAINT MONO (-6460 5535);
FORCEPROP 0 LASTPIN (-6450 5475) $PN 4
J 2
(-6460 5485);
DISPLAY 0.680851 (-6460 5485);
PAINT MONO (-6460 5485);
FORCEPROP 0 LASTPIN (-5850 5725) $PN 8
J 0
(-5840 5735);
DISPLAY 0.680851 (-5840 5735);
PAINT MONO (-5840 5735);
FORCEPROP 0 LASTPIN (-5850 5675) $PN 7
J 0
(-5840 5685);
DISPLAY 0.680851 (-5840 5685);
PAINT MONO (-5840 5685);
FORCEPROP 0 LASTPIN (-5850 5475) $PN 5
J 0
(-5840 5485);
DISPLAY 0.680851 (-5840 5485);
PAINT MONO (-5840 5485);
FORCEPROP 0 LASTPIN (-6450 5775) $PN 6
J 2
(-6460 5785);
DISPLAY 0.680851 (-6460 5785);
PAINT MONO (-6460 5785);
FORCEPROP 0 LASTPIN (-6450 5725) $PN 9
J 2
(-6460 5735);
DISPLAY 0.680851 (-6460 5735);
PAINT MONO (-6460 5735);
FORCEPROP 0 LASTPIN (-5850 5775) $PN 10
J 0
(-5840 5785);
DISPLAY 0.680851 (-5840 5785);
PAINT MONO (-5840 5785);
FORCEPROP 2 LAST PART_TYPE SMLF
J 0
(-6275 6225);
DISPLAY 0.680851 (-6275 6225);
FORCEPROP 2 LAST VALUE PI3CSW12ZUAEX
J 0
(-6275 6175);
DISPLAY 0.680851 (-6275 6175);
FORCEPROP 1 LAST MATERIAL IC
J 0
(-6294 5844);
DISPLAY 0.723404 (-6294 5844);
PAINT GREEN (-6294 5844);
FORCEPROP 2 LAST CDS_LIB pure_quanta
J 2
(-6150 5625);
DISPLAY INVISIBLE (-6150 5625);
FORCEPROP 1 LAST CDS_LMAN_SYM_OUTLINE -150,200,150,-200
J 0
(-6150 5625);
DISPLAY 0.468085 (-6150 5625);
PAINT GREEN (-6150 5625);
DISPLAY INVISIBLE (-6150 5625);
FORCEPROP 1 LAST NEEDS_NO_SIZE TRUE
J 0
(-6150 5625);
DISPLAY 0.723404 (-6150 5625);
PAINT GREEN (-6150 5625);
DISPLAY INVISIBLE (-6150 5625);
FORCEPROP 1 LAST PATH I22
J 0
(-6150 5625);
DISPLAY 0.723404 (-6150 5625);
PAINT GREEN (-6150 5625);
DISPLAY INVISIBLE (-6150 5625);
FORCEPROP 1 LAST PART_NUMBER AL3CSW12000
J 0
(-6294 5971);
DISPLAY 0.723404 (-6294 5971);
PAINT GREEN (-6294 5971);
DISPLAY INVISIBLE (-6294 5971);
FORCEADD UNIVERSAL_POWER..1
(-5600 6350);
FORCEPROP 3 LASTPIN (-5600 6300) SIG_NAME P3V3_AUX\g
J 0
(-5590 6310);
DISPLAY 0.659574 (-5590 6310);
PAINT MONO (-5590 6310);
DISPLAY INVISIBLE (-5590 6310);
FORCEPROP 1 LAST HDL_POWER P3V3_AUX
J 1
(-5600 6400);
DISPLAY 0.489362 (-5600 6400);
PAINT GREEN (-5600 6400);
FORCEPROP 2 LAST CDS_LIB pure_quanta_power
J 0
(-5600 6350);
DISPLAY INVISIBLE (-5600 6350);
FORCEPROP 1 LAST PATH I23
J 0
(-5550 6375);
DISPLAY 0.872340 (-5550 6375);
PAINT AQUA (-5550 6375);
DISPLAY INVISIBLE (-5550 6375);
FORCEADD Q_CAP..1
(-5450 6075);
FORCEPROP 1 LAST LOCATION C1069
J 0
(-5400 6175);
DISPLAY 0.808511 (-5400 6175);
FORCEPROP 0 LAST $SEC 1
J 0
(-5400 6225);
DISPLAY 0.680851 (-5400 6225);
PAINT MONO (-5400 6225);
DISPLAY INVISIBLE (-5400 6225);
FORCEPROP 0 LAST CDS_SEC 1
J 0
(-5400 6225);
DISPLAY 0.680851 (-5400 6225);
DISPLAY INVISIBLE (-5400 6225);
FORCEPROP 1 LASTPIN (-5450 6175) $PN 1
J 0
(-5440 6155);
DISPLAY 0.787234 (-5440 6155);
PAINT MONO (-5440 6155);
FORCEPROP 1 LASTPIN (-5450 5975) $PN 2
J 0
(-5440 5955);
DISPLAY 0.787234 (-5440 5955);
PAINT MONO (-5440 5955);
FORCEPROP 1 LAST MATERIAL X7S
J 0
(-5400 5975);
DISPLAY 0.638298 (-5400 5975);
FORCEPROP 1 LAST PACK_TYPE C0201
J 0
(-5400 5875);
DISPLAY 0.638298 (-5400 5875);
FORCEPROP 1 LAST TOLERANCE 10%
J 0
(-5400 6025);
DISPLAY 0.638298 (-5400 6025);
FORCEPROP 1 LAST VALUE 0.1UF
J 0
(-5400 6125);
DISPLAY 0.638298 (-5400 6125);
FORCEPROP 1 LAST VOLTAGE 10V
J 0
(-5400 6075);
DISPLAY 0.638298 (-5400 6075);
FORCEPROP 2 LAST CDS_LIB pure_quanta
J 0
(-5450 6075);
DISPLAY INVISIBLE (-5450 6075);
FORCEPROP 1 LAST PATH I24
J 0
(-5400 6225);
DISPLAY 0.978723 (-5400 6225);
PAINT WHITE (-5400 6225);
DISPLAY INVISIBLE (-5400 6225);
FORCEPROP 1 LAST PART_NUMBER CH4102K6E00
J 0
(-5400 5925);
DISPLAY 0.638298 (-5400 5925);
DISPLAY INVISIBLE (-5400 5925);
FORCEADD UNIVERSAL_GND..1
(-5450 5875);
FORCEPROP 3 LASTPIN (-5450 5925) SIG_NAME GND\g
J 0
(-5440 5935);
DISPLAY 0.659574 (-5440 5935);
PAINT MONO (-5440 5935);
DISPLAY INVISIBLE (-5440 5935);
FORCEPROP 2 LAST CDS_LIB pure_quanta_power
J 0
(-5450 5875);
DISPLAY INVISIBLE (-5450 5875);
FORCEPROP 1 LAST HDL_POWER GND
J 1
(-5425 5800);
DISPLAY 0.872340 (-5425 5800);
PAINT GREEN (-5425 5800);
DISPLAY INVISIBLE (-5425 5800);
FORCEPROP 1 LAST PATH I25
J 0
(-5375 5875);
DISPLAY 0.872340 (-5375 5875);
PAINT AQUA (-5375 5875);
DISPLAY INVISIBLE (-5375 5875);
FORCEADD OFFPAGE..1
(-7525 5525);
FORCEPROP 2 LAST $XR0 185 
J 0
(-7807 5525);
DISPLAY 0.638298 (-7807 5525);
PAINT MONO (-7807 5525);
FORCEPROP 2 LAST CDS_LIB standard
J 0
(-7525 5525);
DISPLAY INVISIBLE (-7525 5525);
FORCEPROP 1 LAST OFFPAGE TRUE
J 0
(-7200 5400);
DISPLAY 1.170213 (-7200 5400);
PAINT GREEN (-7200 5400);
DISPLAY INVISIBLE (-7200 5400);
FORCEPROP 1 LAST COMMENT_BODY TRUE
J 0
(-7400 5425);
DISPLAY 1.170213 (-7400 5425);
PAINT GREEN (-7400 5425);
DISPLAY INVISIBLE (-7400 5425);
FORCEPROP 2 LAST PATH I26
J 0
(-7475 5600);
DISPLAY 0.680851 (-7475 5600);
DISPLAY INVISIBLE (-7475 5600);
FORCEADD OFFPAGE..3
R 2
(-7525 5575);
FORCEPROP 2 LAST $XR1 321 
J 0
(-7925 5575);
DISPLAY 0.638298 (-7925 5575);
PAINT MONO (-7925 5575);
FORCEPROP 2 LAST $XR0 185 
J 0
(-7805 5575);
DISPLAY 0.638298 (-7805 5575);
PAINT MONO (-7805 5575);
FORCEPROP 2 LAST CDS_LIB standard
J 0
(-7525 5575);
DISPLAY INVISIBLE (-7525 5575);
FORCEPROP 1 LAST OFFPAGE TRUE
J 2
(-7850 5450);
DISPLAY 0.872340 (-7850 5450);
PAINT GREEN (-7850 5450);
DISPLAY INVISIBLE (-7850 5450);
FORCEPROP 1 LAST COMMENT_BODY TRUE
J 2
(-7475 5475);
DISPLAY 0.872340 (-7475 5475);
PAINT GREEN (-7475 5475);
DISPLAY INVISIBLE (-7475 5475);
FORCEPROP 2 LAST PATH I27
J 0
(-7475 5650);
DISPLAY 0.680851 (-7475 5650);
DISPLAY INVISIBLE (-7475 5650);
FORCEADD Q_RES..1
(-7400 5775);
FORCEPROP 1 LAST LOCATION R1215
J 0
(-7250 5775);
DISPLAY 0.787234 (-7250 5775);
PAINT SKYBLUE (-7250 5775);
FORCEPROP 0 LAST $SEC 1
J 0
(-7250 5825);
DISPLAY 0.680851 (-7250 5825);
PAINT MONO (-7250 5825);
DISPLAY INVISIBLE (-7250 5825);
FORCEPROP 0 LAST CDS_SEC 1
J 0
(-7250 5825);
DISPLAY 0.680851 (-7250 5825);
DISPLAY INVISIBLE (-7250 5825);
FORCEPROP 1 LASTPIN (-7500 5775) $PN 1
J 0
(-7488 5787);
DISPLAY 0.787234 (-7488 5787);
PAINT MONO (-7488 5787);
FORCEPROP 1 LASTPIN (-7300 5775) $PN 2
J 0
(-7338 5787);
DISPLAY 0.787234 (-7338 5787);
PAINT MONO (-7338 5787);
FORCEPROP 1 LAST PACK_TYPE 0201LF
J 0
(-7900 5775);
DISPLAY 0.638298 (-7900 5775);
FORCEPROP 1 LAST MATERIAL CHIP
J 0
(-7700 5775);
DISPLAY 0.638298 (-7700 5775);
FORCEPROP 1 LAST VALUE 1K
J 2
(-7500 5775);
DISPLAY 0.638298 (-7500 5775);
FORCEPROP 2 LAST CDS_LIB pure_quanta
J 0
(-7400 5775);
DISPLAY INVISIBLE (-7400 5775);
FORCEPROP 1 LAST TOLERANCE 1%
J 0
(-7425 5975);
DISPLAY 0.978723 (-7425 5975);
DISPLAY INVISIBLE (-7425 5975);
FORCEPROP 1 LAST WATTAGE 1/20W
J 2
(-7025 5975);
DISPLAY 0.978723 (-7025 5975);
DISPLAY INVISIBLE (-7025 5975);
FORCEPROP 1 LAST PATH I28
J 0
(-7450 5925);
DISPLAY 0.978723 (-7450 5925);
PAINT WHITE (-7450 5925);
DISPLAY INVISIBLE (-7450 5925);
FORCEPROP 1 LAST PART_NUMBER CS21001FE07
J 0
(-7450 5875);
DISPLAY 0.978723 (-7450 5875);
DISPLAY INVISIBLE (-7450 5875);
FORCEADD UNIVERSAL_GND..1
R 5
(-8600 5775);
FORCEPROP 3 LASTPIN (-8550 5775) SIG_NAME GND\g
J 0
(-8540 5785);
DISPLAY 0.659574 (-8540 5785);
PAINT MONO (-8540 5785);
DISPLAY INVISIBLE (-8540 5785);
FORCEPROP 2 LAST CDS_LIB pure_quanta_power
R 3
J 0
(-8600 5775);
DISPLAY INVISIBLE (-8600 5775);
FORCEPROP 1 LAST HDL_POWER GND
R 3
J 1
(-8675 5750);
DISPLAY 0.872340 (-8675 5750);
PAINT GREEN (-8675 5750);
DISPLAY INVISIBLE (-8675 5750);
FORCEPROP 1 LAST PATH I29
R 3
J 0
(-8600 5700);
DISPLAY 0.872340 (-8600 5700);
PAINT AQUA (-8600 5700);
DISPLAY INVISIBLE (-8600 5700);
FORCEADD Q_RES..1
(-7400 5725);
FORCEPROP 1 LAST LOCATION R1201
J 0
(-7250 5725);
DISPLAY 0.638298 (-7250 5725);
PAINT SKYBLUE (-7250 5725);
FORCEPROP 0 LAST $SEC 1
J 0
(-7250 5775);
DISPLAY 0.680851 (-7250 5775);
PAINT MONO (-7250 5775);
DISPLAY INVISIBLE (-7250 5775);
FORCEPROP 0 LAST CDS_SEC 1
J 0
(-7250 5775);
DISPLAY 0.680851 (-7250 5775);
DISPLAY INVISIBLE (-7250 5775);
FORCEPROP 1 LASTPIN (-7500 5725) $PN 1
J 0
(-7488 5737);
DISPLAY 0.787234 (-7488 5737);
PAINT MONO (-7488 5737);
FORCEPROP 1 LASTPIN (-7300 5725) $PN 2
J 0
(-7338 5737);
DISPLAY 0.787234 (-7338 5737);
PAINT MONO (-7338 5737);
FORCEPROP 1 LAST PACK_TYPE 0201LF
J 0
(-7825 5725);
DISPLAY 0.510638 (-7825 5725);
FORCEPROP 1 LAST MATERIAL CHIP
J 0
(-7675 5725);
DISPLAY 0.510638 (-7675 5725);
FORCEPROP 1 LAST VALUE 0
J 2
(-7525 5725);
DISPLAY 0.510638 (-7525 5725);
FORCEPROP 1 LAST TOLERANCE 5%
J 0
(-7625 5725);
DISPLAY 0.510638 (-7625 5725);
DISPLAY INVISIBLE (-7625 5725);
FORCEPROP 1 LAST WATTAGE 1/20W
J 2
(-7600 5800);
DISPLAY 0.510638 (-7600 5800);
DISPLAY INVISIBLE (-7600 5800);
FORCEPROP 2 LAST CDS_LIB pure_quanta
J 0
(-7400 5725);
DISPLAY INVISIBLE (-7400 5725);
FORCEPROP 1 LAST PATH I30
J 0
(-7450 5875);
DISPLAY 0.978723 (-7450 5875);
PAINT WHITE (-7450 5875);
DISPLAY INVISIBLE (-7450 5875);
FORCEPROP 1 LAST PART_NUMBER CS00001JE10
J 0
(-7450 5850);
DISPLAY 0.510638 (-7450 5850);
DISPLAY INVISIBLE (-7450 5850);
FORCEADD PI3CSW12ZUAEX..1
(-6225 4200);
FORCEPROP 1 LAST LOCATION U42
J 0
(-6369 4693);
DISPLAY 0.723404 (-6369 4693);
PAINT GREEN (-6369 4693);
FORCEPROP 0 LAST $SEC 1
J 0
(-6350 4850);
DISPLAY 0.680851 (-6350 4850);
PAINT MONO (-6350 4850);
DISPLAY INVISIBLE (-6350 4850);
FORCEPROP 0 LAST CDS_SEC 1
J 0
(-6350 4850);
DISPLAY 0.680851 (-6350 4850);
DISPLAY INVISIBLE (-6350 4850);
FORCEPROP 0 LASTPIN (-6525 4200) $PN 1
J 2
(-6535 4210);
DISPLAY 0.680851 (-6535 4210);
PAINT MONO (-6535 4210);
FORCEPROP 0 LASTPIN (-6525 4150) $PN 2
J 2
(-6535 4160);
DISPLAY 0.680851 (-6535 4160);
PAINT MONO (-6535 4160);
FORCEPROP 0 LASTPIN (-6525 4100) $PN 3
J 2
(-6535 4110);
DISPLAY 0.680851 (-6535 4110);
PAINT MONO (-6535 4110);
FORCEPROP 0 LASTPIN (-6525 4050) $PN 4
J 2
(-6535 4060);
DISPLAY 0.680851 (-6535 4060);
PAINT MONO (-6535 4060);
FORCEPROP 0 LASTPIN (-5925 4300) $PN 8
J 0
(-5915 4310);
DISPLAY 0.680851 (-5915 4310);
PAINT MONO (-5915 4310);
FORCEPROP 0 LASTPIN (-5925 4250) $PN 7
J 0
(-5915 4260);
DISPLAY 0.680851 (-5915 4260);
PAINT MONO (-5915 4260);
FORCEPROP 0 LASTPIN (-5925 4050) $PN 5
J 0
(-5915 4060);
DISPLAY 0.680851 (-5915 4060);
PAINT MONO (-5915 4060);
FORCEPROP 0 LASTPIN (-6525 4350) $PN 6
J 2
(-6535 4360);
DISPLAY 0.680851 (-6535 4360);
PAINT MONO (-6535 4360);
FORCEPROP 0 LASTPIN (-6525 4300) $PN 9
J 2
(-6535 4310);
DISPLAY 0.680851 (-6535 4310);
PAINT MONO (-6535 4310);
FORCEPROP 0 LASTPIN (-5925 4350) $PN 10
J 0
(-5915 4360);
DISPLAY 0.680851 (-5915 4360);
PAINT MONO (-5915 4360);
FORCEPROP 2 LAST PART_TYPE SMLF
J 0
(-6350 4800);
DISPLAY 0.680851 (-6350 4800);
FORCEPROP 1 LAST MATERIAL IC
J 0
(-6369 4419);
DISPLAY 0.723404 (-6369 4419);
PAINT GREEN (-6369 4419);
FORCEPROP 2 LAST VALUE PI3CSW12ZUAEX
J 0
(-6350 4750);
DISPLAY 0.680851 (-6350 4750);
FORCEPROP 2 LAST CDS_LIB pure_quanta
J 2
(-6225 4200);
DISPLAY INVISIBLE (-6225 4200);
FORCEPROP 1 LAST CDS_LMAN_SYM_OUTLINE -150,200,150,-200
J 0
(-6225 4200);
DISPLAY 0.468085 (-6225 4200);
PAINT GREEN (-6225 4200);
DISPLAY INVISIBLE (-6225 4200);
FORCEPROP 1 LAST NEEDS_NO_SIZE TRUE
J 0
(-6225 4200);
DISPLAY 0.723404 (-6225 4200);
PAINT GREEN (-6225 4200);
DISPLAY INVISIBLE (-6225 4200);
FORCEPROP 1 LAST PATH I31
J 0
(-6225 4200);
DISPLAY 0.723404 (-6225 4200);
PAINT GREEN (-6225 4200);
DISPLAY INVISIBLE (-6225 4200);
FORCEPROP 1 LAST PART_NUMBER AL3CSW12000
J 0
(-6369 4546);
DISPLAY 0.723404 (-6369 4546);
PAINT GREEN (-6369 4546);
DISPLAY INVISIBLE (-6369 4546);
FORCEADD OFFPAGE..1
(-7600 4100);
FORCEPROP 2 LAST $XR0 185 
J 0
(-7882 4100);
DISPLAY 0.638298 (-7882 4100);
PAINT MONO (-7882 4100);
FORCEPROP 2 LAST CDS_LIB standard
J 0
(-7600 4100);
DISPLAY INVISIBLE (-7600 4100);
FORCEPROP 1 LAST OFFPAGE TRUE
J 0
(-7275 3975);
DISPLAY 1.170213 (-7275 3975);
PAINT GREEN (-7275 3975);
DISPLAY INVISIBLE (-7275 3975);
FORCEPROP 1 LAST COMMENT_BODY TRUE
J 0
(-7475 4000);
DISPLAY 1.170213 (-7475 4000);
PAINT GREEN (-7475 4000);
DISPLAY INVISIBLE (-7475 4000);
FORCEPROP 2 LAST PATH I32
J 0
(-7550 4175);
DISPLAY 0.680851 (-7550 4175);
DISPLAY INVISIBLE (-7550 4175);
FORCEADD OFFPAGE..3
R 2
(-7600 4050);
FORCEPROP 2 LAST $XR0 185 
J 0
(-7910 4050);
DISPLAY 0.638298 (-7910 4050);
PAINT MONO (-7910 4050);
FORCEPROP 2 LAST CDS_LIB standard
J 2
(-7600 4050);
DISPLAY INVISIBLE (-7600 4050);
FORCEPROP 1 LAST OFFPAGE TRUE
J 2
(-7925 3925);
DISPLAY 0.872340 (-7925 3925);
PAINT GREEN (-7925 3925);
DISPLAY INVISIBLE (-7925 3925);
FORCEPROP 1 LAST COMMENT_BODY TRUE
J 2
(-7550 3950);
DISPLAY 0.872340 (-7550 3950);
PAINT GREEN (-7550 3950);
DISPLAY INVISIBLE (-7550 3950);
FORCEPROP 2 LAST PATH I33
J 0
(-7550 4125);
DISPLAY 0.680851 (-7550 4125);
DISPLAY INVISIBLE (-7550 4125);
FORCEADD OFFPAGE..3
(-5000 4250);
FORCEPROP 2 LAST $XR1 334 
J 0
(-4666 4250);
DISPLAY 0.638298 (-4666 4250);
PAINT MONO (-4666 4250);
FORCEPROP 2 LAST $XR0 185 
J 0
(-4786 4250);
DISPLAY 0.638298 (-4786 4250);
PAINT MONO (-4786 4250);
FORCEPROP 2 LAST CDS_LIB standard
J 2
(-5000 4250);
DISPLAY INVISIBLE (-5000 4250);
FORCEPROP 1 LAST OFFPAGE TRUE
J 0
(-4675 4125);
DISPLAY 0.872340 (-4675 4125);
PAINT GREEN (-4675 4125);
DISPLAY INVISIBLE (-4675 4125);
FORCEPROP 1 LAST COMMENT_BODY TRUE
J 0
(-5050 4150);
DISPLAY 0.872340 (-5050 4150);
PAINT GREEN (-5050 4150);
DISPLAY INVISIBLE (-5050 4150);
FORCEPROP 2 LAST PATH I34
J 0
(-4800 4325);
DISPLAY 0.680851 (-4800 4325);
DISPLAY INVISIBLE (-4800 4325);
FORCEADD OFFPAGE..2
(-5000 4300);
FORCEPROP 2 LAST $XR1 334 
J 0
(-4691 4300);
DISPLAY 0.638298 (-4691 4300);
PAINT MONO (-4691 4300);
FORCEPROP 2 LAST $XR0 185 
J 0
(-4811 4300);
DISPLAY 0.638298 (-4811 4300);
PAINT MONO (-4811 4300);
FORCEPROP 2 LAST CDS_LIB standard
J 2
(-5000 4300);
DISPLAY INVISIBLE (-5000 4300);
FORCEPROP 1 LAST OFFPAGE TRUE
J 0
(-4675 4175);
DISPLAY 0.872340 (-4675 4175);
PAINT GREEN (-4675 4175);
DISPLAY INVISIBLE (-4675 4175);
FORCEPROP 1 LAST COMMENT_BODY TRUE
J 0
(-5045 4205);
DISPLAY 0.872340 (-5045 4205);
PAINT GREEN (-5045 4205);
DISPLAY INVISIBLE (-5045 4205);
FORCEPROP 2 LAST PATH I35
J 0
(-4825 4375);
DISPLAY 0.680851 (-4825 4375);
DISPLAY INVISIBLE (-4825 4375);
FORCEADD UNIVERSAL_GND..1
(-5525 4450);
FORCEPROP 3 LASTPIN (-5525 4500) SIG_NAME GND\g
J 0
(-5515 4510);
DISPLAY 0.659574 (-5515 4510);
PAINT MONO (-5515 4510);
DISPLAY INVISIBLE (-5515 4510);
FORCEPROP 2 LAST CDS_LIB pure_quanta_power
J 0
(-5525 4450);
DISPLAY INVISIBLE (-5525 4450);
FORCEPROP 1 LAST HDL_POWER GND
J 1
(-5500 4375);
DISPLAY 0.872340 (-5500 4375);
PAINT GREEN (-5500 4375);
DISPLAY INVISIBLE (-5500 4375);
FORCEPROP 1 LAST PATH I36
J 0
(-5450 4450);
DISPLAY 0.872340 (-5450 4450);
PAINT AQUA (-5450 4450);
DISPLAY INVISIBLE (-5450 4450);
FORCEADD Q_CAP..1
(-5525 4650);
FORCEPROP 1 LAST LOCATION C1067
J 0
(-5475 4750);
DISPLAY 0.808511 (-5475 4750);
FORCEPROP 0 LAST $SEC 1
J 0
(-5475 4800);
DISPLAY 0.680851 (-5475 4800);
PAINT MONO (-5475 4800);
DISPLAY INVISIBLE (-5475 4800);
FORCEPROP 0 LAST CDS_SEC 1
J 0
(-5475 4800);
DISPLAY 0.680851 (-5475 4800);
DISPLAY INVISIBLE (-5475 4800);
FORCEPROP 1 LASTPIN (-5525 4750) $PN 1
J 0
(-5515 4730);
DISPLAY 0.787234 (-5515 4730);
PAINT MONO (-5515 4730);
FORCEPROP 1 LASTPIN (-5525 4550) $PN 2
J 0
(-5515 4530);
DISPLAY 0.787234 (-5515 4530);
PAINT MONO (-5515 4530);
FORCEPROP 1 LAST MATERIAL X7S
J 0
(-5475 4550);
DISPLAY 0.638298 (-5475 4550);
FORCEPROP 1 LAST PACK_TYPE C0201
J 0
(-5475 4450);
DISPLAY 0.638298 (-5475 4450);
FORCEPROP 1 LAST TOLERANCE 10%
J 0
(-5475 4600);
DISPLAY 0.638298 (-5475 4600);
FORCEPROP 1 LAST VOLTAGE 10V
J 0
(-5475 4650);
DISPLAY 0.638298 (-5475 4650);
FORCEPROP 1 LAST VALUE 0.1UF
J 0
(-5475 4700);
DISPLAY 0.638298 (-5475 4700);
FORCEPROP 2 LAST CDS_LIB pure_quanta
J 0
(-5525 4650);
DISPLAY INVISIBLE (-5525 4650);
FORCEPROP 1 LAST PATH I37
J 0
(-5475 4800);
DISPLAY 0.978723 (-5475 4800);
PAINT WHITE (-5475 4800);
DISPLAY INVISIBLE (-5475 4800);
FORCEPROP 1 LAST PART_NUMBER CH4102K6E00
J 0
(-5475 4500);
DISPLAY 0.638298 (-5475 4500);
DISPLAY INVISIBLE (-5475 4500);
FORCEADD UNIVERSAL_POWER..1
(-5675 4925);
FORCEPROP 3 LASTPIN (-5675 4875) SIG_NAME P3V3_AUX\g
J 0
(-5665 4885);
DISPLAY 0.659574 (-5665 4885);
PAINT MONO (-5665 4885);
DISPLAY INVISIBLE (-5665 4885);
FORCEPROP 1 LAST HDL_POWER P3V3_AUX
J 1
(-5675 4975);
DISPLAY 0.489362 (-5675 4975);
PAINT GREEN (-5675 4975);
FORCEPROP 2 LAST CDS_LIB pure_quanta_power
J 0
(-5675 4925);
DISPLAY INVISIBLE (-5675 4925);
FORCEPROP 1 LAST PATH I38
J 0
(-5625 4950);
DISPLAY 0.872340 (-5625 4950);
PAINT AQUA (-5625 4950);
DISPLAY INVISIBLE (-5625 4950);
FORCEADD UNIVERSAL_GND..1
(-5825 3900);
FORCEPROP 3 LASTPIN (-5825 3950) SIG_NAME GND\g
J 0
(-5815 3960);
DISPLAY 0.659574 (-5815 3960);
PAINT MONO (-5815 3960);
DISPLAY INVISIBLE (-5815 3960);
FORCEPROP 2 LAST CDS_LIB pure_quanta_power
J 0
(-5825 3900);
DISPLAY INVISIBLE (-5825 3900);
FORCEPROP 1 LAST HDL_POWER GND
J 1
(-5800 3825);
DISPLAY 0.872340 (-5800 3825);
PAINT GREEN (-5800 3825);
DISPLAY INVISIBLE (-5800 3825);
FORCEPROP 1 LAST PATH I39
J 0
(-5750 3900);
DISPLAY 0.872340 (-5750 3900);
PAINT AQUA (-5750 3900);
DISPLAY INVISIBLE (-5750 3900);
FORCEADD Q_RES..1
(-7475 4300);
FORCEPROP 1 LAST LOCATION R1199
J 0
(-7325 4300);
DISPLAY 0.638298 (-7325 4300);
PAINT SKYBLUE (-7325 4300);
FORCEPROP 0 LAST $SEC 1
J 0
(-7325 4350);
DISPLAY 0.680851 (-7325 4350);
PAINT MONO (-7325 4350);
DISPLAY INVISIBLE (-7325 4350);
FORCEPROP 0 LAST CDS_SEC 1
J 0
(-7325 4350);
DISPLAY 0.680851 (-7325 4350);
DISPLAY INVISIBLE (-7325 4350);
FORCEPROP 1 LASTPIN (-7575 4300) $PN 1
J 0
(-7563 4312);
DISPLAY 0.787234 (-7563 4312);
PAINT MONO (-7563 4312);
FORCEPROP 1 LASTPIN (-7375 4300) $PN 2
J 0
(-7413 4312);
DISPLAY 0.787234 (-7413 4312);
PAINT MONO (-7413 4312);
FORCEPROP 1 LAST PACK_TYPE 0201LF
J 0
(-7900 4300);
DISPLAY 0.510638 (-7900 4300);
FORCEPROP 1 LAST MATERIAL CHIP
J 0
(-7750 4300);
DISPLAY 0.510638 (-7750 4300);
FORCEPROP 1 LAST VALUE 0
J 2
(-7600 4300);
DISPLAY 0.510638 (-7600 4300);
FORCEPROP 1 LAST TOLERANCE 5%
J 0
(-7700 4300);
DISPLAY 0.510638 (-7700 4300);
DISPLAY INVISIBLE (-7700 4300);
FORCEPROP 1 LAST WATTAGE 1/20W
J 2
(-7675 4375);
DISPLAY 0.510638 (-7675 4375);
DISPLAY INVISIBLE (-7675 4375);
FORCEPROP 2 LAST CDS_LIB pure_quanta
J 0
(-7475 4300);
DISPLAY INVISIBLE (-7475 4300);
FORCEPROP 1 LAST PATH I40
J 0
(-7525 4450);
DISPLAY 0.978723 (-7525 4450);
PAINT WHITE (-7525 4450);
DISPLAY INVISIBLE (-7525 4450);
FORCEPROP 1 LAST PART_NUMBER CS00001JE10
J 0
(-7525 4425);
DISPLAY 0.510638 (-7525 4425);
DISPLAY INVISIBLE (-7525 4425);
FORCEADD Q_RES..1
(-7475 4350);
FORCEPROP 1 LAST LOCATION R1213
J 0
(-7325 4350);
DISPLAY 0.787234 (-7325 4350);
PAINT SKYBLUE (-7325 4350);
FORCEPROP 0 LAST $SEC 1
J 0
(-7325 4400);
DISPLAY 0.680851 (-7325 4400);
PAINT MONO (-7325 4400);
DISPLAY INVISIBLE (-7325 4400);
FORCEPROP 0 LAST CDS_SEC 1
J 0
(-7325 4400);
DISPLAY 0.680851 (-7325 4400);
DISPLAY INVISIBLE (-7325 4400);
FORCEPROP 1 LASTPIN (-7575 4350) $PN 1
J 0
(-7563 4362);
DISPLAY 0.787234 (-7563 4362);
PAINT MONO (-7563 4362);
FORCEPROP 1 LASTPIN (-7375 4350) $PN 2
J 0
(-7413 4362);
DISPLAY 0.787234 (-7413 4362);
PAINT MONO (-7413 4362);
FORCEPROP 1 LAST PACK_TYPE 0201LF
J 0
(-7975 4350);
DISPLAY 0.638298 (-7975 4350);
FORCEPROP 1 LAST MATERIAL CHIP
J 0
(-7775 4350);
DISPLAY 0.638298 (-7775 4350);
FORCEPROP 1 LAST VALUE 1K
J 2
(-7575 4350);
DISPLAY 0.638298 (-7575 4350);
FORCEPROP 2 LAST CDS_LIB pure_quanta
J 0
(-7475 4350);
DISPLAY INVISIBLE (-7475 4350);
FORCEPROP 1 LAST TOLERANCE 1%
J 0
(-7500 4550);
DISPLAY 0.978723 (-7500 4550);
DISPLAY INVISIBLE (-7500 4550);
FORCEPROP 1 LAST WATTAGE 1/20W
J 2
(-7100 4550);
DISPLAY 0.978723 (-7100 4550);
DISPLAY INVISIBLE (-7100 4550);
FORCEPROP 1 LAST PATH I41
J 0
(-7525 4500);
DISPLAY 0.978723 (-7525 4500);
PAINT WHITE (-7525 4500);
DISPLAY INVISIBLE (-7525 4500);
FORCEPROP 1 LAST PART_NUMBER CS21001FE07
J 0
(-7525 4450);
DISPLAY 0.978723 (-7525 4450);
DISPLAY INVISIBLE (-7525 4450);
FORCEADD OFFPAGE..1
(-7600 4200);
FORCEPROP 2 LASTPIN (-7550 4200) SIG_NAME SMB_RT_CPU1_P1_ROM_MUX_1D_SCL
J 0
(-7535 4210);
DISPLAY 0.680851 (-7535 4210);
FORCEPROP 2 LAST $XR1 332 
J 0
(-8002 4200);
DISPLAY 0.638298 (-8002 4200);
PAINT MONO (-8002 4200);
FORCEPROP 2 LAST $XR0 185 
J 0
(-7882 4200);
DISPLAY 0.638298 (-7882 4200);
PAINT MONO (-7882 4200);
FORCEPROP 2 LAST CDS_LIB standard
J 2
(-7600 4200);
DISPLAY INVISIBLE (-7600 4200);
FORCEPROP 1 LAST OFFPAGE TRUE
J 0
(-7275 4075);
DISPLAY 1.170213 (-7275 4075);
PAINT GREEN (-7275 4075);
DISPLAY INVISIBLE (-7275 4075);
FORCEPROP 1 LAST COMMENT_BODY TRUE
J 0
(-7475 4100);
DISPLAY 1.170213 (-7475 4100);
PAINT GREEN (-7475 4100);
DISPLAY INVISIBLE (-7475 4100);
FORCEPROP 2 LAST PATH I42
J 0
(-7550 4275);
DISPLAY 0.680851 (-7550 4275);
DISPLAY INVISIBLE (-7550 4275);
FORCEADD OFFPAGE..3
R 2
(-7600 4150);
FORCEPROP 2 LAST $XR1 332 
J 0
(-8030 4150);
DISPLAY 0.638298 (-8030 4150);
PAINT MONO (-8030 4150);
FORCEPROP 2 LAST $XR0 185 
J 0
(-7910 4150);
DISPLAY 0.638298 (-7910 4150);
PAINT MONO (-7910 4150);
FORCEPROP 2 LAST CDS_LIB standard
J 0
(-7600 4150);
DISPLAY INVISIBLE (-7600 4150);
FORCEPROP 1 LAST OFFPAGE TRUE
J 2
(-7925 4025);
DISPLAY 0.872340 (-7925 4025);
PAINT GREEN (-7925 4025);
DISPLAY INVISIBLE (-7925 4025);
FORCEPROP 1 LAST COMMENT_BODY TRUE
J 2
(-7550 4050);
DISPLAY 0.872340 (-7550 4050);
PAINT GREEN (-7550 4050);
DISPLAY INVISIBLE (-7550 4050);
FORCEPROP 2 LAST PATH I43
J 0
(-7550 4225);
DISPLAY 0.680851 (-7550 4225);
DISPLAY INVISIBLE (-7550 4225);
FORCEADD UNIVERSAL_GND..1
R 5
(-8675 4350);
FORCEPROP 3 LASTPIN (-8625 4350) SIG_NAME GND\g
J 0
(-8615 4360);
DISPLAY 0.659574 (-8615 4360);
PAINT MONO (-8615 4360);
DISPLAY INVISIBLE (-8615 4360);
FORCEPROP 2 LAST CDS_LIB pure_quanta_power
R 3
J 0
(-8675 4350);
DISPLAY INVISIBLE (-8675 4350);
FORCEPROP 1 LAST HDL_POWER GND
R 3
J 1
(-8750 4325);
DISPLAY 0.872340 (-8750 4325);
PAINT GREEN (-8750 4325);
DISPLAY INVISIBLE (-8750 4325);
FORCEPROP 1 LAST PATH I44
R 3
J 0
(-8675 4275);
DISPLAY 0.872340 (-8675 4275);
PAINT AQUA (-8675 4275);
DISPLAY INVISIBLE (-8675 4275);
FORCEADD OFFPAGE..1
(-8775 4300);
FORCEPROP 2 LAST $XR2 186 
J 0
(-9236 4300);
DISPLAY 0.638298 (-9236 4300);
PAINT MONO (-9236 4300);
FORCEPROP 2 LAST $XR1 185 
J 0
(-9116 4300);
DISPLAY 0.638298 (-9116 4300);
PAINT MONO (-9116 4300);
FORCEPROP 2 LAST $XR0 81 
J 0
(-8996 4300);
DISPLAY 0.638298 (-8996 4300);
PAINT MONO (-8996 4300);
FORCEPROP 2 LAST CDS_LIB standard
J 0
(-8775 4300);
DISPLAY INVISIBLE (-8775 4300);
FORCEPROP 1 LAST OFFPAGE TRUE
J 0
(-8450 4175);
DISPLAY 1.170213 (-8450 4175);
PAINT GREEN (-8450 4175);
DISPLAY INVISIBLE (-8450 4175);
FORCEPROP 1 LAST COMMENT_BODY TRUE
J 0
(-8650 4200);
DISPLAY 1.170213 (-8650 4200);
PAINT GREEN (-8650 4200);
DISPLAY INVISIBLE (-8650 4200);
FORCEPROP 2 LAST PATH I45
J 0
(-8725 4375);
DISPLAY 0.680851 (-8725 4375);
DISPLAY INVISIBLE (-8725 4375);
FORCEADD PI3CSW12ZUAEX..1
(-6275 2725);
FORCEPROP 1 LAST LOCATION U41
J 0
(-6419 3218);
DISPLAY 0.723404 (-6419 3218);
PAINT GREEN (-6419 3218);
FORCEPROP 0 LAST $SEC 1
J 0
(-6400 3375);
DISPLAY 0.680851 (-6400 3375);
PAINT MONO (-6400 3375);
DISPLAY INVISIBLE (-6400 3375);
FORCEPROP 0 LAST CDS_SEC 1
J 0
(-6400 3375);
DISPLAY 0.680851 (-6400 3375);
DISPLAY INVISIBLE (-6400 3375);
FORCEPROP 0 LASTPIN (-6575 2725) $PN 1
J 2
(-6585 2735);
DISPLAY 0.680851 (-6585 2735);
PAINT MONO (-6585 2735);
FORCEPROP 0 LASTPIN (-6575 2675) $PN 2
J 2
(-6585 2685);
DISPLAY 0.680851 (-6585 2685);
PAINT MONO (-6585 2685);
FORCEPROP 0 LASTPIN (-6575 2625) $PN 3
J 2
(-6585 2635);
DISPLAY 0.680851 (-6585 2635);
PAINT MONO (-6585 2635);
FORCEPROP 0 LASTPIN (-6575 2575) $PN 4
J 2
(-6585 2585);
DISPLAY 0.680851 (-6585 2585);
PAINT MONO (-6585 2585);
FORCEPROP 0 LASTPIN (-5975 2825) $PN 8
J 0
(-5965 2835);
DISPLAY 0.680851 (-5965 2835);
PAINT MONO (-5965 2835);
FORCEPROP 0 LASTPIN (-5975 2775) $PN 7
J 0
(-5965 2785);
DISPLAY 0.680851 (-5965 2785);
PAINT MONO (-5965 2785);
FORCEPROP 0 LASTPIN (-5975 2575) $PN 5
J 0
(-5965 2585);
DISPLAY 0.680851 (-5965 2585);
PAINT MONO (-5965 2585);
FORCEPROP 0 LASTPIN (-6575 2875) $PN 6
J 2
(-6585 2885);
DISPLAY 0.680851 (-6585 2885);
PAINT MONO (-6585 2885);
FORCEPROP 0 LASTPIN (-6575 2825) $PN 9
J 2
(-6585 2835);
DISPLAY 0.680851 (-6585 2835);
PAINT MONO (-6585 2835);
FORCEPROP 0 LASTPIN (-5975 2875) $PN 10
J 0
(-5965 2885);
DISPLAY 0.680851 (-5965 2885);
PAINT MONO (-5965 2885);
FORCEPROP 2 LAST PART_TYPE SMLF
J 0
(-6400 3325);
DISPLAY 0.680851 (-6400 3325);
FORCEPROP 2 LAST VALUE PI3CSW12ZUAEX
J 0
(-6400 3275);
DISPLAY 0.680851 (-6400 3275);
FORCEPROP 1 LAST MATERIAL IC
J 0
(-6419 2944);
DISPLAY 0.723404 (-6419 2944);
PAINT GREEN (-6419 2944);
FORCEPROP 1 LAST NEEDS_NO_SIZE TRUE
J 0
(-6275 2725);
DISPLAY 0.723404 (-6275 2725);
PAINT GREEN (-6275 2725);
DISPLAY INVISIBLE (-6275 2725);
FORCEPROP 1 LAST CDS_LMAN_SYM_OUTLINE -150,200,150,-200
J 0
(-6275 2725);
DISPLAY 0.468085 (-6275 2725);
PAINT GREEN (-6275 2725);
DISPLAY INVISIBLE (-6275 2725);
FORCEPROP 2 LAST CDS_LIB pure_quanta
J 2
(-6275 2725);
DISPLAY INVISIBLE (-6275 2725);
FORCEPROP 1 LAST PATH I46
J 0
(-6275 2725);
DISPLAY 0.723404 (-6275 2725);
PAINT GREEN (-6275 2725);
DISPLAY INVISIBLE (-6275 2725);
FORCEPROP 1 LAST PART_NUMBER AL3CSW12000
J 0
(-6419 3071);
DISPLAY 0.723404 (-6419 3071);
PAINT GREEN (-6419 3071);
DISPLAY INVISIBLE (-6419 3071);
FORCEADD UNIVERSAL_POWER..1
(-5725 3450);
FORCEPROP 3 LASTPIN (-5725 3400) SIG_NAME P3V3_AUX\g
J 0
(-5715 3410);
DISPLAY 0.659574 (-5715 3410);
PAINT MONO (-5715 3410);
DISPLAY INVISIBLE (-5715 3410);
FORCEPROP 1 LAST HDL_POWER P3V3_AUX
J 1
(-5725 3500);
DISPLAY 0.489362 (-5725 3500);
PAINT GREEN (-5725 3500);
FORCEPROP 2 LAST CDS_LIB pure_quanta_power
J 0
(-5725 3450);
DISPLAY INVISIBLE (-5725 3450);
FORCEPROP 1 LAST PATH I47
J 0
(-5675 3475);
DISPLAY 0.872340 (-5675 3475);
PAINT AQUA (-5675 3475);
DISPLAY INVISIBLE (-5675 3475);
FORCEADD Q_CAP..1
(-5575 3175);
FORCEPROP 1 LAST LOCATION C1066
J 0
(-5525 3275);
DISPLAY 0.808511 (-5525 3275);
FORCEPROP 0 LAST $SEC 1
J 0
(-5525 3325);
DISPLAY 0.680851 (-5525 3325);
PAINT MONO (-5525 3325);
DISPLAY INVISIBLE (-5525 3325);
FORCEPROP 0 LAST CDS_SEC 1
J 0
(-5525 3325);
DISPLAY 0.680851 (-5525 3325);
DISPLAY INVISIBLE (-5525 3325);
FORCEPROP 1 LASTPIN (-5575 3275) $PN 1
J 0
(-5565 3255);
DISPLAY 0.787234 (-5565 3255);
PAINT MONO (-5565 3255);
FORCEPROP 1 LASTPIN (-5575 3075) $PN 2
J 0
(-5565 3055);
DISPLAY 0.787234 (-5565 3055);
PAINT MONO (-5565 3055);
FORCEPROP 1 LAST VALUE 0.1UF
J 0
(-5525 3225);
DISPLAY 0.638298 (-5525 3225);
FORCEPROP 1 LAST VOLTAGE 10V
J 0
(-5525 3175);
DISPLAY 0.638298 (-5525 3175);
FORCEPROP 1 LAST PACK_TYPE C0201
J 0
(-5525 2975);
DISPLAY 0.638298 (-5525 2975);
FORCEPROP 1 LAST TOLERANCE 10%
J 0
(-5525 3125);
DISPLAY 0.638298 (-5525 3125);
FORCEPROP 1 LAST MATERIAL X7S
J 0
(-5525 3075);
DISPLAY 0.638298 (-5525 3075);
FORCEPROP 2 LAST CDS_LIB pure_quanta
J 0
(-5575 3175);
DISPLAY INVISIBLE (-5575 3175);
FORCEPROP 1 LAST PATH I48
J 0
(-5525 3325);
DISPLAY 0.978723 (-5525 3325);
PAINT WHITE (-5525 3325);
DISPLAY INVISIBLE (-5525 3325);
FORCEPROP 1 LAST PART_NUMBER CH4102K6E00
J 0
(-5525 3025);
DISPLAY 0.638298 (-5525 3025);
DISPLAY INVISIBLE (-5525 3025);
FORCEADD OFFPAGE..2
(-5050 2825);
FORCEPROP 2 LAST $XR1 356 
J 0
(-4741 2825);
DISPLAY 0.638298 (-4741 2825);
PAINT MONO (-4741 2825);
FORCEPROP 2 LAST $XR0 185 
J 0
(-4861 2825);
DISPLAY 0.638298 (-4861 2825);
PAINT MONO (-4861 2825);
FORCEPROP 2 LAST CDS_LIB standard
J 2
(-5050 2825);
DISPLAY INVISIBLE (-5050 2825);
FORCEPROP 1 LAST OFFPAGE TRUE
J 0
(-4725 2700);
DISPLAY 0.872340 (-4725 2700);
PAINT GREEN (-4725 2700);
DISPLAY INVISIBLE (-4725 2700);
FORCEPROP 1 LAST COMMENT_BODY TRUE
J 0
(-5095 2730);
DISPLAY 0.872340 (-5095 2730);
PAINT GREEN (-5095 2730);
DISPLAY INVISIBLE (-5095 2730);
FORCEPROP 2 LAST PATH I49
J 0
(-4875 2900);
DISPLAY 0.680851 (-4875 2900);
DISPLAY INVISIBLE (-4875 2900);
FORCEADD OFFPAGE..3
(-5050 2775);
FORCEPROP 2 LAST $XR1 356 
J 0
(-4716 2775);
DISPLAY 0.638298 (-4716 2775);
PAINT MONO (-4716 2775);
FORCEPROP 2 LAST $XR0 185 
J 0
(-4836 2775);
DISPLAY 0.638298 (-4836 2775);
PAINT MONO (-4836 2775);
FORCEPROP 2 LAST CDS_LIB standard
J 2
(-5050 2775);
DISPLAY INVISIBLE (-5050 2775);
FORCEPROP 1 LAST OFFPAGE TRUE
J 0
(-4725 2650);
DISPLAY 0.872340 (-4725 2650);
PAINT GREEN (-4725 2650);
DISPLAY INVISIBLE (-4725 2650);
FORCEPROP 1 LAST COMMENT_BODY TRUE
J 0
(-5100 2675);
DISPLAY 0.872340 (-5100 2675);
PAINT GREEN (-5100 2675);
DISPLAY INVISIBLE (-5100 2675);
FORCEPROP 2 LAST PATH I50
J 0
(-4850 2850);
DISPLAY 0.680851 (-4850 2850);
DISPLAY INVISIBLE (-4850 2850);
FORCEADD UNIVERSAL_GND..1
(-5575 2975);
FORCEPROP 3 LASTPIN (-5575 3025) SIG_NAME GND\g
J 0
(-5565 3035);
DISPLAY 0.659574 (-5565 3035);
PAINT MONO (-5565 3035);
DISPLAY INVISIBLE (-5565 3035);
FORCEPROP 2 LAST CDS_LIB pure_quanta_power
J 0
(-5575 2975);
DISPLAY INVISIBLE (-5575 2975);
FORCEPROP 1 LAST HDL_POWER GND
J 1
(-5550 2900);
DISPLAY 0.872340 (-5550 2900);
PAINT GREEN (-5550 2900);
DISPLAY INVISIBLE (-5550 2900);
FORCEPROP 1 LAST PATH I51
J 0
(-5500 2975);
DISPLAY 0.872340 (-5500 2975);
PAINT AQUA (-5500 2975);
DISPLAY INVISIBLE (-5500 2975);
FORCEADD UNIVERSAL_GND..1
(-5875 2425);
FORCEPROP 3 LASTPIN (-5875 2475) SIG_NAME GND\g
J 0
(-5865 2485);
DISPLAY 0.659574 (-5865 2485);
PAINT MONO (-5865 2485);
DISPLAY INVISIBLE (-5865 2485);
FORCEPROP 2 LAST CDS_LIB pure_quanta_power
J 0
(-5875 2425);
DISPLAY INVISIBLE (-5875 2425);
FORCEPROP 1 LAST HDL_POWER GND
J 1
(-5850 2350);
DISPLAY 0.872340 (-5850 2350);
PAINT GREEN (-5850 2350);
DISPLAY INVISIBLE (-5850 2350);
FORCEPROP 1 LAST PATH I52
J 0
(-5800 2425);
DISPLAY 0.872340 (-5800 2425);
PAINT AQUA (-5800 2425);
DISPLAY INVISIBLE (-5800 2425);
FORCEADD Q_RES..1
(-7525 2825);
FORCEPROP 1 LAST LOCATION R1198
J 0
(-7375 2825);
DISPLAY 0.638298 (-7375 2825);
PAINT SKYBLUE (-7375 2825);
FORCEPROP 0 LAST $SEC 1
J 0
(-7375 2875);
DISPLAY 0.680851 (-7375 2875);
PAINT MONO (-7375 2875);
DISPLAY INVISIBLE (-7375 2875);
FORCEPROP 0 LAST CDS_SEC 1
J 0
(-7375 2875);
DISPLAY 0.680851 (-7375 2875);
DISPLAY INVISIBLE (-7375 2875);
FORCEPROP 1 LASTPIN (-7625 2825) $PN 1
J 0
(-7613 2837);
DISPLAY 0.787234 (-7613 2837);
PAINT MONO (-7613 2837);
FORCEPROP 1 LASTPIN (-7425 2825) $PN 2
J 0
(-7463 2837);
DISPLAY 0.787234 (-7463 2837);
PAINT MONO (-7463 2837);
FORCEPROP 1 LAST VALUE 0
J 2
(-7650 2825);
DISPLAY 0.510638 (-7650 2825);
FORCEPROP 1 LAST MATERIAL CHIP
J 0
(-7800 2825);
DISPLAY 0.510638 (-7800 2825);
FORCEPROP 1 LAST PACK_TYPE 0201LF
J 0
(-7950 2825);
DISPLAY 0.510638 (-7950 2825);
FORCEPROP 2 LAST CDS_LIB pure_quanta
J 0
(-7525 2825);
DISPLAY INVISIBLE (-7525 2825);
FORCEPROP 1 LAST WATTAGE 1/20W
J 2
(-7725 2900);
DISPLAY 0.510638 (-7725 2900);
DISPLAY INVISIBLE (-7725 2900);
FORCEPROP 1 LAST TOLERANCE 5%
J 0
(-7750 2825);
DISPLAY 0.510638 (-7750 2825);
DISPLAY INVISIBLE (-7750 2825);
FORCEPROP 1 LAST PATH I53
J 0
(-7575 2975);
DISPLAY 0.978723 (-7575 2975);
PAINT WHITE (-7575 2975);
DISPLAY INVISIBLE (-7575 2975);
FORCEPROP 1 LAST PART_NUMBER CS00001JE10
J 0
(-7575 2950);
DISPLAY 0.510638 (-7575 2950);
DISPLAY INVISIBLE (-7575 2950);
FORCEADD Q_RES..1
(-7525 2875);
FORCEPROP 1 LAST LOCATION R1212
J 0
(-7375 2875);
DISPLAY 0.787234 (-7375 2875);
PAINT SKYBLUE (-7375 2875);
FORCEPROP 0 LAST $SEC 1
J 0
(-7375 2925);
DISPLAY 0.680851 (-7375 2925);
PAINT MONO (-7375 2925);
DISPLAY INVISIBLE (-7375 2925);
FORCEPROP 0 LAST CDS_SEC 1
J 0
(-7375 2925);
DISPLAY 0.680851 (-7375 2925);
DISPLAY INVISIBLE (-7375 2925);
FORCEPROP 1 LASTPIN (-7625 2875) $PN 1
J 0
(-7613 2887);
DISPLAY 0.787234 (-7613 2887);
PAINT MONO (-7613 2887);
FORCEPROP 1 LASTPIN (-7425 2875) $PN 2
J 0
(-7463 2887);
DISPLAY 0.787234 (-7463 2887);
PAINT MONO (-7463 2887);
FORCEPROP 1 LAST VALUE 1K
J 2
(-7625 2875);
DISPLAY 0.638298 (-7625 2875);
FORCEPROP 1 LAST MATERIAL CHIP
J 0
(-7825 2875);
DISPLAY 0.638298 (-7825 2875);
FORCEPROP 1 LAST PACK_TYPE 0201LF
J 0
(-8025 2875);
DISPLAY 0.638298 (-8025 2875);
FORCEPROP 1 LAST WATTAGE 1/20W
J 2
(-7150 3075);
DISPLAY 0.978723 (-7150 3075);
DISPLAY INVISIBLE (-7150 3075);
FORCEPROP 1 LAST TOLERANCE 1%
J 0
(-7550 3075);
DISPLAY 0.978723 (-7550 3075);
DISPLAY INVISIBLE (-7550 3075);
FORCEPROP 2 LAST CDS_LIB pure_quanta
J 0
(-7525 2875);
DISPLAY INVISIBLE (-7525 2875);
FORCEPROP 1 LAST PATH I54
J 0
(-7575 3025);
DISPLAY 0.978723 (-7575 3025);
PAINT WHITE (-7575 3025);
DISPLAY INVISIBLE (-7575 3025);
FORCEPROP 1 LAST PART_NUMBER CS21001FE07
J 0
(-7575 2975);
DISPLAY 0.978723 (-7575 2975);
DISPLAY INVISIBLE (-7575 2975);
FORCEADD OFFPAGE..1
(-7650 2725);
FORCEPROP 2 LASTPIN (-7600 2725) SIG_NAME SMB_RT_CPU1_P3_ROM_MUX_1D_SCL
J 0
(-7585 2735);
DISPLAY 0.680851 (-7585 2735);
FORCEPROP 2 LAST $XR1 354 
J 0
(-8022 2725);
DISPLAY 0.638298 (-8022 2725);
PAINT MONO (-8022 2725);
FORCEPROP 2 LAST $XR0 185 
J 0
(-7902 2725);
DISPLAY 0.638298 (-7902 2725);
PAINT MONO (-7902 2725);
FORCEPROP 2 LAST CDS_LIB standard
J 2
(-7650 2725);
DISPLAY INVISIBLE (-7650 2725);
FORCEPROP 1 LAST OFFPAGE TRUE
J 0
(-7325 2600);
DISPLAY 1.170213 (-7325 2600);
PAINT GREEN (-7325 2600);
DISPLAY INVISIBLE (-7325 2600);
FORCEPROP 1 LAST COMMENT_BODY TRUE
J 0
(-7525 2625);
DISPLAY 1.170213 (-7525 2625);
PAINT GREEN (-7525 2625);
DISPLAY INVISIBLE (-7525 2625);
FORCEPROP 2 LAST PATH I55
J 0
(-7600 2800);
DISPLAY 0.680851 (-7600 2800);
DISPLAY INVISIBLE (-7600 2800);
FORCEADD OFFPAGE..1
(-7650 2625);
FORCEPROP 2 LAST $XR0 185 
J 0
(-7932 2625);
DISPLAY 0.638298 (-7932 2625);
PAINT MONO (-7932 2625);
FORCEPROP 2 LAST CDS_LIB standard
J 0
(-7650 2625);
DISPLAY INVISIBLE (-7650 2625);
FORCEPROP 1 LAST OFFPAGE TRUE
J 0
(-7325 2500);
DISPLAY 1.170213 (-7325 2500);
PAINT GREEN (-7325 2500);
DISPLAY INVISIBLE (-7325 2500);
FORCEPROP 1 LAST COMMENT_BODY TRUE
J 0
(-7525 2525);
DISPLAY 1.170213 (-7525 2525);
PAINT GREEN (-7525 2525);
DISPLAY INVISIBLE (-7525 2525);
FORCEPROP 2 LAST PATH I56
J 0
(-7600 2700);
DISPLAY 0.680851 (-7600 2700);
DISPLAY INVISIBLE (-7600 2700);
FORCEADD OFFPAGE..3
R 2
(-7650 2575);
FORCEPROP 2 LAST $XR0 185 
J 0
(-7930 2575);
DISPLAY 0.638298 (-7930 2575);
PAINT MONO (-7930 2575);
FORCEPROP 2 LAST CDS_LIB standard
J 2
(-7650 2575);
DISPLAY INVISIBLE (-7650 2575);
FORCEPROP 1 LAST OFFPAGE TRUE
J 2
(-7975 2450);
DISPLAY 0.872340 (-7975 2450);
PAINT GREEN (-7975 2450);
DISPLAY INVISIBLE (-7975 2450);
FORCEPROP 1 LAST COMMENT_BODY TRUE
J 2
(-7600 2475);
DISPLAY 0.872340 (-7600 2475);
PAINT GREEN (-7600 2475);
DISPLAY INVISIBLE (-7600 2475);
FORCEPROP 2 LAST PATH I57
J 0
(-7600 2650);
DISPLAY 0.680851 (-7600 2650);
DISPLAY INVISIBLE (-7600 2650);
FORCEADD OFFPAGE..3
R 2
(-7650 2675);
FORCEPROP 2 LAST $XR1 354 
J 0
(-8050 2675);
DISPLAY 0.638298 (-8050 2675);
PAINT MONO (-8050 2675);
FORCEPROP 2 LAST $XR0 185 
J 0
(-7930 2675);
DISPLAY 0.638298 (-7930 2675);
PAINT MONO (-7930 2675);
FORCEPROP 2 LAST CDS_LIB standard
J 0
(-7650 2675);
DISPLAY INVISIBLE (-7650 2675);
FORCEPROP 1 LAST OFFPAGE TRUE
J 2
(-7975 2550);
DISPLAY 0.872340 (-7975 2550);
PAINT GREEN (-7975 2550);
DISPLAY INVISIBLE (-7975 2550);
FORCEPROP 1 LAST COMMENT_BODY TRUE
J 2
(-7600 2575);
DISPLAY 0.872340 (-7600 2575);
PAINT GREEN (-7600 2575);
DISPLAY INVISIBLE (-7600 2575);
FORCEPROP 2 LAST PATH I58
J 0
(-7600 2750);
DISPLAY 0.680851 (-7600 2750);
DISPLAY INVISIBLE (-7600 2750);
FORCEADD UNIVERSAL_GND..1
R 5
(-8725 2875);
FORCEPROP 3 LASTPIN (-8675 2875) SIG_NAME GND\g
J 0
(-8665 2885);
DISPLAY 0.659574 (-8665 2885);
PAINT MONO (-8665 2885);
DISPLAY INVISIBLE (-8665 2885);
FORCEPROP 2 LAST CDS_LIB pure_quanta_power
R 3
J 0
(-8725 2875);
DISPLAY INVISIBLE (-8725 2875);
FORCEPROP 1 LAST HDL_POWER GND
R 3
J 1
(-8800 2850);
DISPLAY 0.872340 (-8800 2850);
PAINT GREEN (-8800 2850);
DISPLAY INVISIBLE (-8800 2850);
FORCEPROP 1 LAST PATH I59
R 3
J 0
(-8725 2800);
DISPLAY 0.872340 (-8725 2800);
PAINT AQUA (-8725 2800);
DISPLAY INVISIBLE (-8725 2800);
FORCEADD OFFPAGE..1
(-8825 2825);
FORCEPROP 2 LAST $XR2 186 
J 0
(-9316 2825);
DISPLAY 0.638298 (-9316 2825);
PAINT MONO (-9316 2825);
FORCEPROP 2 LAST $XR1 185 
J 0
(-9196 2825);
DISPLAY 0.638298 (-9196 2825);
PAINT MONO (-9196 2825);
FORCEPROP 2 LAST $XR0 81 
J 0
(-9076 2825);
DISPLAY 0.638298 (-9076 2825);
PAINT MONO (-9076 2825);
FORCEPROP 2 LAST CDS_LIB standard
J 0
(-8825 2825);
DISPLAY INVISIBLE (-8825 2825);
FORCEPROP 1 LAST OFFPAGE TRUE
J 0
(-8500 2700);
DISPLAY 1.170213 (-8500 2700);
PAINT GREEN (-8500 2700);
DISPLAY INVISIBLE (-8500 2700);
FORCEPROP 1 LAST COMMENT_BODY TRUE
J 0
(-8700 2725);
DISPLAY 1.170213 (-8700 2725);
PAINT GREEN (-8700 2725);
DISPLAY INVISIBLE (-8700 2725);
FORCEPROP 2 LAST PATH I60
J 0
(-8775 2900);
DISPLAY 0.680851 (-8775 2900);
DISPLAY INVISIBLE (-8775 2900);
FORCEADD PI3CSW12ZUAEX..1
(-6225 1125);
FORCEPROP 1 LAST LOCATION U43
J 0
(-6369 1618);
DISPLAY 0.723404 (-6369 1618);
PAINT GREEN (-6369 1618);
FORCEPROP 0 LAST $SEC 1
J 0
(-6350 1775);
DISPLAY 0.680851 (-6350 1775);
PAINT MONO (-6350 1775);
DISPLAY INVISIBLE (-6350 1775);
FORCEPROP 0 LAST CDS_SEC 1
J 0
(-6350 1775);
DISPLAY 0.680851 (-6350 1775);
DISPLAY INVISIBLE (-6350 1775);
FORCEPROP 0 LASTPIN (-6525 1125) $PN 1
J 2
(-6535 1135);
DISPLAY 0.680851 (-6535 1135);
PAINT MONO (-6535 1135);
FORCEPROP 0 LASTPIN (-6525 1075) $PN 2
J 2
(-6535 1085);
DISPLAY 0.680851 (-6535 1085);
PAINT MONO (-6535 1085);
FORCEPROP 0 LASTPIN (-6525 1025) $PN 3
J 2
(-6535 1035);
DISPLAY 0.680851 (-6535 1035);
PAINT MONO (-6535 1035);
FORCEPROP 0 LASTPIN (-6525 975) $PN 4
J 2
(-6535 985);
DISPLAY 0.680851 (-6535 985);
PAINT MONO (-6535 985);
FORCEPROP 0 LASTPIN (-5925 1225) $PN 8
J 0
(-5915 1235);
DISPLAY 0.680851 (-5915 1235);
PAINT MONO (-5915 1235);
FORCEPROP 0 LASTPIN (-5925 1175) $PN 7
J 0
(-5915 1185);
DISPLAY 0.680851 (-5915 1185);
PAINT MONO (-5915 1185);
FORCEPROP 0 LASTPIN (-5925 975) $PN 5
J 0
(-5915 985);
DISPLAY 0.680851 (-5915 985);
PAINT MONO (-5915 985);
FORCEPROP 0 LASTPIN (-6525 1275) $PN 6
J 2
(-6535 1285);
DISPLAY 0.680851 (-6535 1285);
PAINT MONO (-6535 1285);
FORCEPROP 0 LASTPIN (-6525 1225) $PN 9
J 2
(-6535 1235);
DISPLAY 0.680851 (-6535 1235);
PAINT MONO (-6535 1235);
FORCEPROP 0 LASTPIN (-5925 1275) $PN 10
J 0
(-5915 1285);
DISPLAY 0.680851 (-5915 1285);
PAINT MONO (-5915 1285);
FORCEPROP 2 LAST PART_TYPE SMLF
J 0
(-6350 1725);
DISPLAY 0.680851 (-6350 1725);
FORCEPROP 2 LAST VALUE PI3CSW12ZUAEX
J 0
(-6350 1675);
DISPLAY 0.680851 (-6350 1675);
FORCEPROP 1 LAST MATERIAL IC
J 0
(-6369 1344);
DISPLAY 0.723404 (-6369 1344);
PAINT GREEN (-6369 1344);
FORCEPROP 1 LAST NEEDS_NO_SIZE TRUE
J 0
(-6225 1125);
DISPLAY 0.723404 (-6225 1125);
PAINT GREEN (-6225 1125);
DISPLAY INVISIBLE (-6225 1125);
FORCEPROP 1 LAST CDS_LMAN_SYM_OUTLINE -150,200,150,-200
J 0
(-6225 1125);
DISPLAY 0.468085 (-6225 1125);
PAINT GREEN (-6225 1125);
DISPLAY INVISIBLE (-6225 1125);
FORCEPROP 2 LAST CDS_LIB pure_quanta
J 2
(-6225 1125);
DISPLAY INVISIBLE (-6225 1125);
FORCEPROP 1 LAST PATH I61
J 0
(-6225 1125);
DISPLAY 0.723404 (-6225 1125);
PAINT GREEN (-6225 1125);
DISPLAY INVISIBLE (-6225 1125);
FORCEPROP 1 LAST PART_NUMBER AL3CSW12000
J 0
(-6369 1471);
DISPLAY 0.723404 (-6369 1471);
PAINT GREEN (-6369 1471);
DISPLAY INVISIBLE (-6369 1471);
FORCEADD OFFPAGE..2
(-5000 1225);
FORCEPROP 2 LAST $XR1 345 
J 0
(-4691 1225);
DISPLAY 0.638298 (-4691 1225);
PAINT MONO (-4691 1225);
FORCEPROP 2 LAST $XR0 185 
J 0
(-4811 1225);
DISPLAY 0.638298 (-4811 1225);
PAINT MONO (-4811 1225);
FORCEPROP 2 LAST CDS_LIB standard
J 2
(-5000 1225);
DISPLAY INVISIBLE (-5000 1225);
FORCEPROP 1 LAST OFFPAGE TRUE
J 0
(-4675 1100);
DISPLAY 0.872340 (-4675 1100);
PAINT GREEN (-4675 1100);
DISPLAY INVISIBLE (-4675 1100);
FORCEPROP 1 LAST COMMENT_BODY TRUE
J 0
(-5045 1130);
DISPLAY 0.872340 (-5045 1130);
PAINT GREEN (-5045 1130);
DISPLAY INVISIBLE (-5045 1130);
FORCEPROP 2 LAST PATH I62
J 0
(-4825 1300);
DISPLAY 0.680851 (-4825 1300);
DISPLAY INVISIBLE (-4825 1300);
FORCEADD OFFPAGE..3
(-5000 1175);
FORCEPROP 2 LAST $XR1 345 
J 0
(-4666 1175);
DISPLAY 0.638298 (-4666 1175);
PAINT MONO (-4666 1175);
FORCEPROP 2 LAST $XR0 185 
J 0
(-4786 1175);
DISPLAY 0.638298 (-4786 1175);
PAINT MONO (-4786 1175);
FORCEPROP 2 LAST CDS_LIB standard
J 2
(-5000 1175);
DISPLAY INVISIBLE (-5000 1175);
FORCEPROP 1 LAST OFFPAGE TRUE
J 0
(-4675 1050);
DISPLAY 0.872340 (-4675 1050);
PAINT GREEN (-4675 1050);
DISPLAY INVISIBLE (-4675 1050);
FORCEPROP 1 LAST COMMENT_BODY TRUE
J 0
(-5050 1075);
DISPLAY 0.872340 (-5050 1075);
PAINT GREEN (-5050 1075);
DISPLAY INVISIBLE (-5050 1075);
FORCEPROP 2 LAST PATH I63
J 0
(-4800 1250);
DISPLAY 0.680851 (-4800 1250);
DISPLAY INVISIBLE (-4800 1250);
FORCEADD UNIVERSAL_GND..1
(-5525 1375);
FORCEPROP 3 LASTPIN (-5525 1425) SIG_NAME GND\g
J 0
(-5515 1435);
DISPLAY 0.659574 (-5515 1435);
PAINT MONO (-5515 1435);
DISPLAY INVISIBLE (-5515 1435);
FORCEPROP 2 LAST CDS_LIB pure_quanta_power
J 0
(-5525 1375);
DISPLAY INVISIBLE (-5525 1375);
FORCEPROP 1 LAST HDL_POWER GND
J 1
(-5500 1300);
DISPLAY 0.872340 (-5500 1300);
PAINT GREEN (-5500 1300);
DISPLAY INVISIBLE (-5500 1300);
FORCEPROP 1 LAST PATH I64
J 0
(-5450 1375);
DISPLAY 0.872340 (-5450 1375);
PAINT AQUA (-5450 1375);
DISPLAY INVISIBLE (-5450 1375);
FORCEADD Q_CAP..1
(-5525 1575);
FORCEPROP 1 LAST LOCATION C1068
J 0
(-5475 1675);
DISPLAY 0.808511 (-5475 1675);
FORCEPROP 0 LAST $SEC 1
J 0
(-5475 1725);
DISPLAY 0.680851 (-5475 1725);
PAINT MONO (-5475 1725);
DISPLAY INVISIBLE (-5475 1725);
FORCEPROP 0 LAST CDS_SEC 1
J 0
(-5475 1725);
DISPLAY 0.680851 (-5475 1725);
DISPLAY INVISIBLE (-5475 1725);
FORCEPROP 1 LASTPIN (-5525 1675) $PN 1
J 0
(-5515 1655);
DISPLAY 0.787234 (-5515 1655);
PAINT MONO (-5515 1655);
FORCEPROP 1 LASTPIN (-5525 1475) $PN 2
J 0
(-5515 1455);
DISPLAY 0.787234 (-5515 1455);
PAINT MONO (-5515 1455);
FORCEPROP 1 LAST VALUE 0.1UF
J 0
(-5475 1625);
DISPLAY 0.638298 (-5475 1625);
FORCEPROP 1 LAST VOLTAGE 10V
J 0
(-5475 1575);
DISPLAY 0.638298 (-5475 1575);
FORCEPROP 1 LAST PACK_TYPE C0201
J 0
(-5475 1375);
DISPLAY 0.638298 (-5475 1375);
FORCEPROP 1 LAST TOLERANCE 10%
J 0
(-5475 1525);
DISPLAY 0.638298 (-5475 1525);
FORCEPROP 1 LAST MATERIAL X7S
J 0
(-5475 1475);
DISPLAY 0.638298 (-5475 1475);
FORCEPROP 2 LAST CDS_LIB pure_quanta
J 0
(-5525 1575);
DISPLAY INVISIBLE (-5525 1575);
FORCEPROP 1 LAST PATH I65
J 0
(-5475 1725);
DISPLAY 0.978723 (-5475 1725);
PAINT WHITE (-5475 1725);
DISPLAY INVISIBLE (-5475 1725);
FORCEPROP 1 LAST PART_NUMBER CH4102K6E00
J 0
(-5475 1425);
DISPLAY 0.638298 (-5475 1425);
DISPLAY INVISIBLE (-5475 1425);
FORCEADD UNIVERSAL_POWER..1
(-5675 1850);
FORCEPROP 3 LASTPIN (-5675 1800) SIG_NAME P3V3_AUX\g
J 0
(-5665 1810);
DISPLAY 0.659574 (-5665 1810);
PAINT MONO (-5665 1810);
DISPLAY INVISIBLE (-5665 1810);
FORCEPROP 1 LAST HDL_POWER P3V3_AUX
J 1
(-5675 1900);
DISPLAY 0.489362 (-5675 1900);
PAINT GREEN (-5675 1900);
FORCEPROP 2 LAST CDS_LIB pure_quanta_power
J 0
(-5675 1850);
DISPLAY INVISIBLE (-5675 1850);
FORCEPROP 1 LAST PATH I66
J 0
(-5625 1875);
DISPLAY 0.872340 (-5625 1875);
PAINT AQUA (-5625 1875);
DISPLAY INVISIBLE (-5625 1875);
FORCEADD UNIVERSAL_GND..1
(-5825 825);
FORCEPROP 3 LASTPIN (-5825 875) SIG_NAME GND\g
J 0
(-5815 885);
DISPLAY 0.659574 (-5815 885);
PAINT MONO (-5815 885);
DISPLAY INVISIBLE (-5815 885);
FORCEPROP 2 LAST CDS_LIB pure_quanta_power
J 0
(-5825 825);
DISPLAY INVISIBLE (-5825 825);
FORCEPROP 1 LAST HDL_POWER GND
J 1
(-5800 750);
DISPLAY 0.872340 (-5800 750);
PAINT GREEN (-5800 750);
DISPLAY INVISIBLE (-5800 750);
FORCEPROP 1 LAST PATH I67
J 0
(-5750 825);
DISPLAY 0.872340 (-5750 825);
PAINT AQUA (-5750 825);
DISPLAY INVISIBLE (-5750 825);
FORCEADD Q_RES..1
(-7475 1225);
FORCEPROP 1 LAST LOCATION R1200
J 0
(-7325 1225);
DISPLAY 0.638298 (-7325 1225);
PAINT SKYBLUE (-7325 1225);
FORCEPROP 0 LAST $SEC 1
J 0
(-7325 1275);
DISPLAY 0.680851 (-7325 1275);
PAINT MONO (-7325 1275);
DISPLAY INVISIBLE (-7325 1275);
FORCEPROP 0 LAST CDS_SEC 1
J 0
(-7325 1275);
DISPLAY 0.680851 (-7325 1275);
DISPLAY INVISIBLE (-7325 1275);
FORCEPROP 1 LASTPIN (-7575 1225) $PN 1
J 0
(-7563 1237);
DISPLAY 0.787234 (-7563 1237);
PAINT MONO (-7563 1237);
FORCEPROP 1 LASTPIN (-7375 1225) $PN 2
J 0
(-7413 1237);
DISPLAY 0.787234 (-7413 1237);
PAINT MONO (-7413 1237);
FORCEPROP 1 LAST VALUE 0
J 2
(-7600 1225);
DISPLAY 0.510638 (-7600 1225);
FORCEPROP 1 LAST MATERIAL CHIP
J 0
(-7750 1225);
DISPLAY 0.510638 (-7750 1225);
FORCEPROP 1 LAST PACK_TYPE 0201LF
J 0
(-7900 1225);
DISPLAY 0.510638 (-7900 1225);
FORCEPROP 2 LAST CDS_LIB pure_quanta
J 0
(-7475 1225);
DISPLAY INVISIBLE (-7475 1225);
FORCEPROP 1 LAST WATTAGE 1/20W
J 2
(-7675 1300);
DISPLAY 0.510638 (-7675 1300);
DISPLAY INVISIBLE (-7675 1300);
FORCEPROP 1 LAST TOLERANCE 5%
J 0
(-7700 1225);
DISPLAY 0.510638 (-7700 1225);
DISPLAY INVISIBLE (-7700 1225);
FORCEPROP 1 LAST PATH I68
J 0
(-7525 1375);
DISPLAY 0.978723 (-7525 1375);
PAINT WHITE (-7525 1375);
DISPLAY INVISIBLE (-7525 1375);
FORCEPROP 1 LAST PART_NUMBER CS00001JE10
J 0
(-7525 1350);
DISPLAY 0.510638 (-7525 1350);
DISPLAY INVISIBLE (-7525 1350);
FORCEADD Q_RES..1
(-7475 1275);
FORCEPROP 1 LAST LOCATION R1214
J 0
(-7325 1275);
DISPLAY 0.787234 (-7325 1275);
PAINT SKYBLUE (-7325 1275);
FORCEPROP 0 LAST $SEC 1
J 0
(-7325 1325);
DISPLAY 0.680851 (-7325 1325);
PAINT MONO (-7325 1325);
DISPLAY INVISIBLE (-7325 1325);
FORCEPROP 0 LAST CDS_SEC 1
J 0
(-7325 1325);
DISPLAY 0.680851 (-7325 1325);
DISPLAY INVISIBLE (-7325 1325);
FORCEPROP 1 LASTPIN (-7575 1275) $PN 1
J 0
(-7563 1287);
DISPLAY 0.787234 (-7563 1287);
PAINT MONO (-7563 1287);
FORCEPROP 1 LASTPIN (-7375 1275) $PN 2
J 0
(-7413 1287);
DISPLAY 0.787234 (-7413 1287);
PAINT MONO (-7413 1287);
FORCEPROP 1 LAST PACK_TYPE 0201LF
J 0
(-7975 1275);
DISPLAY 0.638298 (-7975 1275);
FORCEPROP 1 LAST MATERIAL CHIP
J 0
(-7775 1275);
DISPLAY 0.638298 (-7775 1275);
FORCEPROP 1 LAST VALUE 1K
J 2
(-7575 1275);
DISPLAY 0.638298 (-7575 1275);
FORCEPROP 2 LAST CDS_LIB pure_quanta
J 0
(-7475 1275);
DISPLAY INVISIBLE (-7475 1275);
FORCEPROP 1 LAST TOLERANCE 1%
J 0
(-7500 1475);
DISPLAY 0.978723 (-7500 1475);
DISPLAY INVISIBLE (-7500 1475);
FORCEPROP 1 LAST WATTAGE 1/20W
J 2
(-7100 1475);
DISPLAY 0.978723 (-7100 1475);
DISPLAY INVISIBLE (-7100 1475);
FORCEPROP 1 LAST PATH I69
J 0
(-7525 1425);
DISPLAY 0.978723 (-7525 1425);
PAINT WHITE (-7525 1425);
DISPLAY INVISIBLE (-7525 1425);
FORCEPROP 1 LAST PART_NUMBER CS21001FE07
J 0
(-7525 1375);
DISPLAY 0.978723 (-7525 1375);
DISPLAY INVISIBLE (-7525 1375);
FORCEADD OFFPAGE..1
(-7600 1125);
FORCEPROP 2 LASTPIN (-7550 1125) SIG_NAME SMB_RT_CPU1_P2_ROM_MUX_1D_SCL
J 0
(-7535 1135);
DISPLAY 0.680851 (-7535 1135);
FORCEPROP 2 LAST $XR1 343 
J 0
(-8002 1125);
DISPLAY 0.638298 (-8002 1125);
PAINT MONO (-8002 1125);
FORCEPROP 2 LAST $XR0 185 
J 0
(-7882 1125);
DISPLAY 0.638298 (-7882 1125);
PAINT MONO (-7882 1125);
FORCEPROP 2 LAST CDS_LIB standard
J 2
(-7600 1125);
DISPLAY INVISIBLE (-7600 1125);
FORCEPROP 1 LAST OFFPAGE TRUE
J 0
(-7275 1000);
DISPLAY 1.170213 (-7275 1000);
PAINT GREEN (-7275 1000);
DISPLAY INVISIBLE (-7275 1000);
FORCEPROP 1 LAST COMMENT_BODY TRUE
J 0
(-7475 1025);
DISPLAY 1.170213 (-7475 1025);
PAINT GREEN (-7475 1025);
DISPLAY INVISIBLE (-7475 1025);
FORCEPROP 2 LAST PATH I70
J 0
(-7550 1200);
DISPLAY 0.680851 (-7550 1200);
DISPLAY INVISIBLE (-7550 1200);
FORCEADD OFFPAGE..3
R 2
(-7600 1075);
FORCEPROP 2 LAST $XR1 343 
J 0
(-8030 1075);
DISPLAY 0.638298 (-8030 1075);
PAINT MONO (-8030 1075);
FORCEPROP 2 LAST $XR0 185 
J 0
(-7910 1075);
DISPLAY 0.638298 (-7910 1075);
PAINT MONO (-7910 1075);
FORCEPROP 2 LAST CDS_LIB standard
J 0
(-7600 1075);
DISPLAY INVISIBLE (-7600 1075);
FORCEPROP 1 LAST OFFPAGE TRUE
J 2
(-7925 950);
DISPLAY 0.872340 (-7925 950);
PAINT GREEN (-7925 950);
DISPLAY INVISIBLE (-7925 950);
FORCEPROP 1 LAST COMMENT_BODY TRUE
J 2
(-7550 975);
DISPLAY 0.872340 (-7550 975);
PAINT GREEN (-7550 975);
DISPLAY INVISIBLE (-7550 975);
FORCEPROP 2 LAST PATH I71
J 0
(-7550 1150);
DISPLAY 0.680851 (-7550 1150);
DISPLAY INVISIBLE (-7550 1150);
FORCEADD OFFPAGE..1
(-7600 1025);
FORCEPROP 2 LAST $XR0 185 
J 0
(-7882 1025);
DISPLAY 0.638298 (-7882 1025);
PAINT MONO (-7882 1025);
FORCEPROP 2 LAST CDS_LIB standard
J 0
(-7600 1025);
DISPLAY INVISIBLE (-7600 1025);
FORCEPROP 1 LAST OFFPAGE TRUE
J 0
(-7275 900);
DISPLAY 1.170213 (-7275 900);
PAINT GREEN (-7275 900);
DISPLAY INVISIBLE (-7275 900);
FORCEPROP 1 LAST COMMENT_BODY TRUE
J 0
(-7475 925);
DISPLAY 1.170213 (-7475 925);
PAINT GREEN (-7475 925);
DISPLAY INVISIBLE (-7475 925);
FORCEPROP 2 LAST PATH I72
J 0
(-7550 1100);
DISPLAY 0.680851 (-7550 1100);
DISPLAY INVISIBLE (-7550 1100);
FORCEADD OFFPAGE..3
R 2
(-7600 975);
FORCEPROP 2 LAST $XR0 185 
J 0
(-7910 975);
DISPLAY 0.638298 (-7910 975);
PAINT MONO (-7910 975);
FORCEPROP 2 LAST CDS_LIB standard
J 2
(-7600 975);
DISPLAY INVISIBLE (-7600 975);
FORCEPROP 1 LAST OFFPAGE TRUE
J 2
(-7925 850);
DISPLAY 0.872340 (-7925 850);
PAINT GREEN (-7925 850);
DISPLAY INVISIBLE (-7925 850);
FORCEPROP 1 LAST COMMENT_BODY TRUE
J 2
(-7550 875);
DISPLAY 0.872340 (-7550 875);
PAINT GREEN (-7550 875);
DISPLAY INVISIBLE (-7550 875);
FORCEPROP 2 LAST PATH I73
J 0
(-7550 1050);
DISPLAY 0.680851 (-7550 1050);
DISPLAY INVISIBLE (-7550 1050);
FORCEADD UNIVERSAL_GND..1
R 5
(-8675 1275);
FORCEPROP 3 LASTPIN (-8625 1275) SIG_NAME GND\g
J 0
(-8615 1285);
DISPLAY 0.659574 (-8615 1285);
PAINT MONO (-8615 1285);
DISPLAY INVISIBLE (-8615 1285);
FORCEPROP 2 LAST CDS_LIB pure_quanta_power
R 3
J 0
(-8675 1275);
DISPLAY INVISIBLE (-8675 1275);
FORCEPROP 1 LAST HDL_POWER GND
R 3
J 1
(-8750 1250);
DISPLAY 0.872340 (-8750 1250);
PAINT GREEN (-8750 1250);
DISPLAY INVISIBLE (-8750 1250);
FORCEPROP 1 LAST PATH I74
R 3
J 0
(-8675 1200);
DISPLAY 0.872340 (-8675 1200);
PAINT AQUA (-8675 1200);
DISPLAY INVISIBLE (-8675 1200);
FORCEADD OFFPAGE..1
(-8775 1225);
FORCEPROP 2 LAST $XR2 186 
J 0
(-9236 1225);
DISPLAY 0.638298 (-9236 1225);
PAINT MONO (-9236 1225);
FORCEPROP 2 LAST $XR1 185 
J 0
(-9116 1225);
DISPLAY 0.638298 (-9116 1225);
PAINT MONO (-9116 1225);
FORCEPROP 2 LAST $XR0 81 
J 0
(-8996 1225);
DISPLAY 0.638298 (-8996 1225);
PAINT MONO (-8996 1225);
FORCEPROP 2 LAST CDS_LIB standard
J 0
(-8775 1225);
DISPLAY INVISIBLE (-8775 1225);
FORCEPROP 1 LAST OFFPAGE TRUE
J 0
(-8450 1100);
DISPLAY 1.170213 (-8450 1100);
PAINT GREEN (-8450 1100);
DISPLAY INVISIBLE (-8450 1100);
FORCEPROP 1 LAST COMMENT_BODY TRUE
J 0
(-8650 1125);
DISPLAY 1.170213 (-8650 1125);
PAINT GREEN (-8650 1125);
DISPLAY INVISIBLE (-8650 1125);
FORCEPROP 2 LAST PATH I75
J 0
(-8725 1300);
DISPLAY 0.680851 (-8725 1300);
DISPLAY INVISIBLE (-8725 1300);
FORCEADD PI3CSW12ZUAEX..1
(-1850 3575);
FORCEPROP 1 LAST LOCATION U48
J 0
(-1994 4068);
DISPLAY 0.723404 (-1994 4068);
PAINT GREEN (-1994 4068);
FORCEPROP 0 LAST $SEC 1
J 0
(-1975 4225);
DISPLAY 0.680851 (-1975 4225);
PAINT MONO (-1975 4225);
DISPLAY INVISIBLE (-1975 4225);
FORCEPROP 0 LAST CDS_SEC 1
J 0
(-1975 4225);
DISPLAY 0.680851 (-1975 4225);
DISPLAY INVISIBLE (-1975 4225);
FORCEPROP 0 LASTPIN (-2150 3575) $PN 1
J 2
(-2160 3585);
DISPLAY 0.680851 (-2160 3585);
PAINT MONO (-2160 3585);
FORCEPROP 0 LASTPIN (-2150 3525) $PN 2
J 2
(-2160 3535);
DISPLAY 0.680851 (-2160 3535);
PAINT MONO (-2160 3535);
FORCEPROP 0 LASTPIN (-2150 3475) $PN 3
J 2
(-2160 3485);
DISPLAY 0.680851 (-2160 3485);
PAINT MONO (-2160 3485);
FORCEPROP 0 LASTPIN (-2150 3425) $PN 4
J 2
(-2160 3435);
DISPLAY 0.680851 (-2160 3435);
PAINT MONO (-2160 3435);
FORCEPROP 0 LASTPIN (-1550 3675) $PN 8
J 0
(-1540 3685);
DISPLAY 0.680851 (-1540 3685);
PAINT MONO (-1540 3685);
FORCEPROP 0 LASTPIN (-1550 3625) $PN 7
J 0
(-1540 3635);
DISPLAY 0.680851 (-1540 3635);
PAINT MONO (-1540 3635);
FORCEPROP 0 LASTPIN (-1550 3425) $PN 5
J 0
(-1540 3435);
DISPLAY 0.680851 (-1540 3435);
PAINT MONO (-1540 3435);
FORCEPROP 0 LASTPIN (-2150 3725) $PN 6
J 2
(-2160 3735);
DISPLAY 0.680851 (-2160 3735);
PAINT MONO (-2160 3735);
FORCEPROP 0 LASTPIN (-2150 3675) $PN 9
J 2
(-2160 3685);
DISPLAY 0.680851 (-2160 3685);
PAINT MONO (-2160 3685);
FORCEPROP 0 LASTPIN (-1550 3725) $PN 10
J 0
(-1540 3735);
DISPLAY 0.680851 (-1540 3735);
PAINT MONO (-1540 3735);
FORCEPROP 2 LAST PART_TYPE SMLF
J 0
(-1975 4175);
DISPLAY 0.680851 (-1975 4175);
FORCEPROP 1 LAST MATERIAL IC
J 0
(-1994 3794);
DISPLAY 0.723404 (-1994 3794);
PAINT GREEN (-1994 3794);
FORCEPROP 2 LAST VALUE PI3CSW12ZUAEX
J 0
(-1975 4125);
DISPLAY 0.680851 (-1975 4125);
FORCEPROP 2 LAST CDS_LIB pure_quanta
J 2
(-1850 3575);
DISPLAY INVISIBLE (-1850 3575);
FORCEPROP 1 LAST CDS_LMAN_SYM_OUTLINE -150,200,150,-200
J 0
(-1850 3575);
DISPLAY 0.468085 (-1850 3575);
PAINT GREEN (-1850 3575);
DISPLAY INVISIBLE (-1850 3575);
FORCEPROP 1 LAST NEEDS_NO_SIZE TRUE
J 0
(-1850 3575);
DISPLAY 0.723404 (-1850 3575);
PAINT GREEN (-1850 3575);
DISPLAY INVISIBLE (-1850 3575);
FORCEPROP 1 LAST PATH I76
J 0
(-1850 3575);
DISPLAY 0.723404 (-1850 3575);
PAINT GREEN (-1850 3575);
DISPLAY INVISIBLE (-1850 3575);
FORCEPROP 1 LAST PART_NUMBER AL3CSW12000
J 0
(-1994 3921);
DISPLAY 0.723404 (-1994 3921);
PAINT GREEN (-1994 3921);
DISPLAY INVISIBLE (-1994 3921);
FORCEADD OFFPAGE..2
(-550 5200);
FORCEPROP 2 LAST $XR1 279 
J 0
(-241 5200);
DISPLAY 0.638298 (-241 5200);
PAINT MONO (-241 5200);
FORCEPROP 2 LAST $XR0 185 
J 0
(-361 5200);
DISPLAY 0.638298 (-361 5200);
PAINT MONO (-361 5200);
FORCEPROP 2 LAST CDS_LIB standard
J 2
(-550 5200);
DISPLAY INVISIBLE (-550 5200);
FORCEPROP 1 LAST OFFPAGE TRUE
J 0
(-225 5075);
DISPLAY 0.872340 (-225 5075);
PAINT GREEN (-225 5075);
DISPLAY INVISIBLE (-225 5075);
FORCEPROP 1 LAST COMMENT_BODY TRUE
J 0
(-595 5105);
DISPLAY 0.872340 (-595 5105);
PAINT GREEN (-595 5105);
DISPLAY INVISIBLE (-595 5105);
FORCEPROP 2 LAST PATH I77
J 0
(-375 5275);
DISPLAY 0.680851 (-375 5275);
DISPLAY INVISIBLE (-375 5275);
FORCEADD OFFPAGE..3
(-550 5150);
FORCEPROP 2 LAST $XR1 279 
J 0
(-216 5150);
DISPLAY 0.638298 (-216 5150);
PAINT MONO (-216 5150);
FORCEPROP 2 LAST $XR0 185 
J 0
(-336 5150);
DISPLAY 0.638298 (-336 5150);
PAINT MONO (-336 5150);
FORCEPROP 2 LAST CDS_LIB standard
J 2
(-550 5150);
DISPLAY INVISIBLE (-550 5150);
FORCEPROP 1 LAST OFFPAGE TRUE
J 0
(-225 5025);
DISPLAY 0.872340 (-225 5025);
PAINT GREEN (-225 5025);
DISPLAY INVISIBLE (-225 5025);
FORCEPROP 1 LAST COMMENT_BODY TRUE
J 0
(-600 5050);
DISPLAY 0.872340 (-600 5050);
PAINT GREEN (-600 5050);
DISPLAY INVISIBLE (-600 5050);
FORCEPROP 2 LAST PATH I78
J 0
(-350 5225);
DISPLAY 0.680851 (-350 5225);
DISPLAY INVISIBLE (-350 5225);
FORCEADD UNIVERSAL_GND..1
(-1075 5350);
FORCEPROP 3 LASTPIN (-1075 5400) SIG_NAME GND\g
J 0
(-1065 5410);
DISPLAY 0.659574 (-1065 5410);
PAINT MONO (-1065 5410);
DISPLAY INVISIBLE (-1065 5410);
FORCEPROP 2 LAST CDS_LIB pure_quanta_power
J 0
(-1075 5350);
DISPLAY INVISIBLE (-1075 5350);
FORCEPROP 1 LAST HDL_POWER GND
J 1
(-1050 5275);
DISPLAY 0.872340 (-1050 5275);
PAINT GREEN (-1050 5275);
DISPLAY INVISIBLE (-1050 5275);
FORCEPROP 1 LAST PATH I79
J 0
(-1000 5350);
DISPLAY 0.872340 (-1000 5350);
PAINT AQUA (-1000 5350);
DISPLAY INVISIBLE (-1000 5350);
FORCEADD Q_CAP..1
(-1075 5550);
FORCEPROP 1 LAST LOCATION C1073
J 0
(-1025 5650);
DISPLAY 0.808511 (-1025 5650);
FORCEPROP 0 LAST $SEC 1
J 0
(-1025 5700);
DISPLAY 0.680851 (-1025 5700);
PAINT MONO (-1025 5700);
DISPLAY INVISIBLE (-1025 5700);
FORCEPROP 0 LAST CDS_SEC 1
J 0
(-1025 5700);
DISPLAY 0.680851 (-1025 5700);
DISPLAY INVISIBLE (-1025 5700);
FORCEPROP 1 LASTPIN (-1075 5650) $PN 1
J 0
(-1065 5630);
DISPLAY 0.787234 (-1065 5630);
PAINT MONO (-1065 5630);
FORCEPROP 1 LASTPIN (-1075 5450) $PN 2
J 0
(-1065 5430);
DISPLAY 0.787234 (-1065 5430);
PAINT MONO (-1065 5430);
FORCEPROP 1 LAST MATERIAL X7S
J 0
(-1025 5450);
DISPLAY 0.638298 (-1025 5450);
FORCEPROP 1 LAST PACK_TYPE C0201
J 0
(-1025 5350);
DISPLAY 0.638298 (-1025 5350);
FORCEPROP 1 LAST TOLERANCE 10%
J 0
(-1025 5500);
DISPLAY 0.638298 (-1025 5500);
FORCEPROP 1 LAST VOLTAGE 10V
J 0
(-1025 5550);
DISPLAY 0.638298 (-1025 5550);
FORCEPROP 1 LAST VALUE 0.1UF
J 0
(-1025 5600);
DISPLAY 0.638298 (-1025 5600);
FORCEPROP 2 LAST CDS_LIB pure_quanta
J 0
(-1075 5550);
DISPLAY INVISIBLE (-1075 5550);
FORCEPROP 1 LAST PATH I80
J 0
(-1025 5700);
DISPLAY 0.978723 (-1025 5700);
PAINT WHITE (-1025 5700);
DISPLAY INVISIBLE (-1025 5700);
FORCEPROP 1 LAST PART_NUMBER CH4102K6E00
J 0
(-1025 5400);
DISPLAY 0.638298 (-1025 5400);
DISPLAY INVISIBLE (-1025 5400);
FORCEADD UNIVERSAL_POWER..1
(-1225 5825);
FORCEPROP 3 LASTPIN (-1225 5775) SIG_NAME P3V3_AUX\g
J 0
(-1215 5785);
DISPLAY 0.659574 (-1215 5785);
PAINT MONO (-1215 5785);
DISPLAY INVISIBLE (-1215 5785);
FORCEPROP 1 LAST HDL_POWER P3V3_AUX
J 1
(-1225 5875);
DISPLAY 0.489362 (-1225 5875);
PAINT GREEN (-1225 5875);
FORCEPROP 2 LAST CDS_LIB pure_quanta_power
J 0
(-1225 5825);
DISPLAY INVISIBLE (-1225 5825);
FORCEPROP 1 LAST PATH I81
J 0
(-1175 5850);
DISPLAY 0.872340 (-1175 5850);
PAINT AQUA (-1175 5850);
DISPLAY INVISIBLE (-1175 5850);
FORCEADD UNIVERSAL_GND..1
(-1375 4800);
FORCEPROP 3 LASTPIN (-1375 4850) SIG_NAME GND\g
J 0
(-1365 4860);
DISPLAY 0.659574 (-1365 4860);
PAINT MONO (-1365 4860);
DISPLAY INVISIBLE (-1365 4860);
FORCEPROP 2 LAST CDS_LIB pure_quanta_power
J 0
(-1375 4800);
DISPLAY INVISIBLE (-1375 4800);
FORCEPROP 1 LAST HDL_POWER GND
J 1
(-1350 4725);
DISPLAY 0.872340 (-1350 4725);
PAINT GREEN (-1350 4725);
DISPLAY INVISIBLE (-1350 4725);
FORCEPROP 1 LAST PATH I82
J 0
(-1300 4800);
DISPLAY 0.872340 (-1300 4800);
PAINT AQUA (-1300 4800);
DISPLAY INVISIBLE (-1300 4800);
FORCEADD UNIVERSAL_POWER..1
(-1300 4300);
FORCEPROP 3 LASTPIN (-1300 4250) SIG_NAME P3V3_AUX\g
J 0
(-1290 4260);
DISPLAY 0.659574 (-1290 4260);
PAINT MONO (-1290 4260);
DISPLAY INVISIBLE (-1290 4260);
FORCEPROP 1 LAST HDL_POWER P3V3_AUX
J 1
(-1300 4350);
DISPLAY 0.489362 (-1300 4350);
PAINT GREEN (-1300 4350);
FORCEPROP 2 LAST CDS_LIB pure_quanta_power
J 0
(-1300 4300);
DISPLAY INVISIBLE (-1300 4300);
FORCEPROP 1 LAST PATH I83
J 0
(-1250 4325);
DISPLAY 0.872340 (-1250 4325);
PAINT AQUA (-1250 4325);
DISPLAY INVISIBLE (-1250 4325);
FORCEADD Q_CAP..1
(-1150 4025);
FORCEPROP 1 LAST LOCATION C1072
J 0
(-1100 4125);
DISPLAY 0.808511 (-1100 4125);
FORCEPROP 0 LAST $SEC 1
J 0
(-1100 4175);
DISPLAY 0.680851 (-1100 4175);
PAINT MONO (-1100 4175);
DISPLAY INVISIBLE (-1100 4175);
FORCEPROP 0 LAST CDS_SEC 1
J 0
(-1100 4175);
DISPLAY 0.680851 (-1100 4175);
DISPLAY INVISIBLE (-1100 4175);
FORCEPROP 1 LASTPIN (-1150 4125) $PN 1
J 0
(-1140 4105);
DISPLAY 0.787234 (-1140 4105);
PAINT MONO (-1140 4105);
FORCEPROP 1 LASTPIN (-1150 3925) $PN 2
J 0
(-1140 3905);
DISPLAY 0.787234 (-1140 3905);
PAINT MONO (-1140 3905);
FORCEPROP 1 LAST MATERIAL X7S
J 0
(-1100 3925);
DISPLAY 0.638298 (-1100 3925);
FORCEPROP 1 LAST PACK_TYPE C0201
J 0
(-1100 3825);
DISPLAY 0.638298 (-1100 3825);
FORCEPROP 1 LAST TOLERANCE 10%
J 0
(-1100 3975);
DISPLAY 0.638298 (-1100 3975);
FORCEPROP 1 LAST VOLTAGE 10V
J 0
(-1100 4025);
DISPLAY 0.638298 (-1100 4025);
FORCEPROP 1 LAST VALUE 0.1UF
J 0
(-1100 4075);
DISPLAY 0.638298 (-1100 4075);
FORCEPROP 2 LAST CDS_LIB pure_quanta
J 0
(-1150 4025);
DISPLAY INVISIBLE (-1150 4025);
FORCEPROP 1 LAST PATH I84
J 0
(-1100 4175);
DISPLAY 0.978723 (-1100 4175);
PAINT WHITE (-1100 4175);
DISPLAY INVISIBLE (-1100 4175);
FORCEPROP 1 LAST PART_NUMBER CH4102K6E00
J 0
(-1100 3875);
DISPLAY 0.638298 (-1100 3875);
DISPLAY INVISIBLE (-1100 3875);
FORCEADD PI3CSW12ZUAEX..1
(-1775 5100);
FORCEPROP 1 LAST LOCATION U49
J 0
(-1919 5593);
DISPLAY 0.723404 (-1919 5593);
PAINT GREEN (-1919 5593);
FORCEPROP 0 LAST $SEC 1
J 0
(-1900 5750);
DISPLAY 0.680851 (-1900 5750);
PAINT MONO (-1900 5750);
DISPLAY INVISIBLE (-1900 5750);
FORCEPROP 0 LAST CDS_SEC 1
J 0
(-1900 5750);
DISPLAY 0.680851 (-1900 5750);
DISPLAY INVISIBLE (-1900 5750);
FORCEPROP 0 LASTPIN (-2075 5100) $PN 1
J 2
(-2085 5110);
DISPLAY 0.680851 (-2085 5110);
PAINT MONO (-2085 5110);
FORCEPROP 0 LASTPIN (-2075 5050) $PN 2
J 2
(-2085 5060);
DISPLAY 0.680851 (-2085 5060);
PAINT MONO (-2085 5060);
FORCEPROP 0 LASTPIN (-2075 5000) $PN 3
J 2
(-2085 5010);
DISPLAY 0.680851 (-2085 5010);
PAINT MONO (-2085 5010);
FORCEPROP 0 LASTPIN (-2075 4950) $PN 4
J 2
(-2085 4960);
DISPLAY 0.680851 (-2085 4960);
PAINT MONO (-2085 4960);
FORCEPROP 0 LASTPIN (-1475 5200) $PN 8
J 0
(-1465 5210);
DISPLAY 0.680851 (-1465 5210);
PAINT MONO (-1465 5210);
FORCEPROP 0 LASTPIN (-1475 5150) $PN 7
J 0
(-1465 5160);
DISPLAY 0.680851 (-1465 5160);
PAINT MONO (-1465 5160);
FORCEPROP 0 LASTPIN (-1475 4950) $PN 5
J 0
(-1465 4960);
DISPLAY 0.680851 (-1465 4960);
PAINT MONO (-1465 4960);
FORCEPROP 0 LASTPIN (-2075 5250) $PN 6
J 2
(-2085 5260);
DISPLAY 0.680851 (-2085 5260);
PAINT MONO (-2085 5260);
FORCEPROP 0 LASTPIN (-2075 5200) $PN 9
J 2
(-2085 5210);
DISPLAY 0.680851 (-2085 5210);
PAINT MONO (-2085 5210);
FORCEPROP 0 LASTPIN (-1475 5250) $PN 10
J 0
(-1465 5260);
DISPLAY 0.680851 (-1465 5260);
PAINT MONO (-1465 5260);
FORCEPROP 2 LAST PART_TYPE SMLF
J 0
(-1900 5700);
DISPLAY 0.680851 (-1900 5700);
FORCEPROP 2 LAST VALUE PI3CSW12ZUAEX
J 0
(-1900 5650);
DISPLAY 0.680851 (-1900 5650);
FORCEPROP 1 LAST MATERIAL IC
J 0
(-1919 5319);
DISPLAY 0.723404 (-1919 5319);
PAINT GREEN (-1919 5319);
FORCEPROP 2 LAST CDS_LIB pure_quanta
J 2
(-1775 5100);
DISPLAY INVISIBLE (-1775 5100);
FORCEPROP 1 LAST CDS_LMAN_SYM_OUTLINE -150,200,150,-200
J 0
(-1775 5100);
DISPLAY 0.468085 (-1775 5100);
PAINT GREEN (-1775 5100);
DISPLAY INVISIBLE (-1775 5100);
FORCEPROP 1 LAST NEEDS_NO_SIZE TRUE
J 0
(-1775 5100);
DISPLAY 0.723404 (-1775 5100);
PAINT GREEN (-1775 5100);
DISPLAY INVISIBLE (-1775 5100);
FORCEPROP 1 LAST PATH I85
J 0
(-1775 5100);
DISPLAY 0.723404 (-1775 5100);
PAINT GREEN (-1775 5100);
DISPLAY INVISIBLE (-1775 5100);
FORCEPROP 1 LAST PART_NUMBER AL3CSW12000
J 0
(-1919 5446);
DISPLAY 0.723404 (-1919 5446);
PAINT GREEN (-1919 5446);
DISPLAY INVISIBLE (-1919 5446);
FORCEADD Q_RES..1
(-3025 5200);
FORCEPROP 1 LAST LOCATION R1211
J 0
(-2875 5200);
DISPLAY 0.638298 (-2875 5200);
PAINT SKYBLUE (-2875 5200);
FORCEPROP 0 LAST $SEC 1
J 0
(-2875 5250);
DISPLAY 0.680851 (-2875 5250);
PAINT MONO (-2875 5250);
DISPLAY INVISIBLE (-2875 5250);
FORCEPROP 0 LAST CDS_SEC 1
J 0
(-2875 5250);
DISPLAY 0.680851 (-2875 5250);
DISPLAY INVISIBLE (-2875 5250);
FORCEPROP 1 LASTPIN (-3125 5200) $PN 1
J 0
(-3113 5212);
DISPLAY 0.787234 (-3113 5212);
PAINT MONO (-3113 5212);
FORCEPROP 1 LASTPIN (-2925 5200) $PN 2
J 0
(-2963 5212);
DISPLAY 0.787234 (-2963 5212);
PAINT MONO (-2963 5212);
FORCEPROP 1 LAST PACK_TYPE 0201LF
J 0
(-3450 5200);
DISPLAY 0.510638 (-3450 5200);
FORCEPROP 1 LAST MATERIAL CHIP
J 0
(-3300 5200);
DISPLAY 0.510638 (-3300 5200);
FORCEPROP 1 LAST VALUE 0
J 2
(-3150 5200);
DISPLAY 0.510638 (-3150 5200);
FORCEPROP 1 LAST TOLERANCE 5%
J 0
(-3250 5200);
DISPLAY 0.510638 (-3250 5200);
DISPLAY INVISIBLE (-3250 5200);
FORCEPROP 1 LAST WATTAGE 1/20W
J 2
(-3225 5275);
DISPLAY 0.510638 (-3225 5275);
DISPLAY INVISIBLE (-3225 5275);
FORCEPROP 2 LAST CDS_LIB pure_quanta
J 0
(-3025 5200);
DISPLAY INVISIBLE (-3025 5200);
FORCEPROP 1 LAST PATH I86
J 0
(-3075 5350);
DISPLAY 0.978723 (-3075 5350);
PAINT WHITE (-3075 5350);
DISPLAY INVISIBLE (-3075 5350);
FORCEPROP 1 LAST PART_NUMBER CS00001JE10
J 0
(-3075 5325);
DISPLAY 0.510638 (-3075 5325);
DISPLAY INVISIBLE (-3075 5325);
FORCEADD Q_RES..1
(-3025 5250);
FORCEPROP 1 LAST LOCATION R1219
J 0
(-2875 5250);
DISPLAY 0.787234 (-2875 5250);
PAINT SKYBLUE (-2875 5250);
FORCEPROP 0 LAST $SEC 1
J 0
(-2875 5300);
DISPLAY 0.680851 (-2875 5300);
PAINT MONO (-2875 5300);
DISPLAY INVISIBLE (-2875 5300);
FORCEPROP 0 LAST CDS_SEC 1
J 0
(-2875 5300);
DISPLAY 0.680851 (-2875 5300);
DISPLAY INVISIBLE (-2875 5300);
FORCEPROP 1 LASTPIN (-3125 5250) $PN 1
J 0
(-3113 5262);
DISPLAY 0.787234 (-3113 5262);
PAINT MONO (-3113 5262);
FORCEPROP 1 LASTPIN (-2925 5250) $PN 2
J 0
(-2963 5262);
DISPLAY 0.787234 (-2963 5262);
PAINT MONO (-2963 5262);
FORCEPROP 1 LAST PACK_TYPE 0201LF
J 0
(-3525 5250);
DISPLAY 0.638298 (-3525 5250);
FORCEPROP 1 LAST MATERIAL CHIP
J 0
(-3325 5250);
DISPLAY 0.638298 (-3325 5250);
FORCEPROP 1 LAST VALUE 1K
J 2
(-3125 5250);
DISPLAY 0.638298 (-3125 5250);
FORCEPROP 2 LAST CDS_LIB pure_quanta
J 0
(-3025 5250);
DISPLAY INVISIBLE (-3025 5250);
FORCEPROP 1 LAST TOLERANCE 1%
J 0
(-3050 5450);
DISPLAY 0.978723 (-3050 5450);
DISPLAY INVISIBLE (-3050 5450);
FORCEPROP 1 LAST WATTAGE 1/20W
J 2
(-2650 5450);
DISPLAY 0.978723 (-2650 5450);
DISPLAY INVISIBLE (-2650 5450);
FORCEPROP 1 LAST PATH I87
J 0
(-3075 5400);
DISPLAY 0.978723 (-3075 5400);
PAINT WHITE (-3075 5400);
DISPLAY INVISIBLE (-3075 5400);
FORCEPROP 1 LAST PART_NUMBER CS21001FE07
J 0
(-3075 5350);
DISPLAY 0.978723 (-3075 5350);
DISPLAY INVISIBLE (-3075 5350);
FORCEADD OFFPAGE..1
(-3150 5100);
FORCEPROP 2 LASTPIN (-3100 5100) SIG_NAME SMB_RT_CPU0_P0_ROM_MUX_1D_SCL
J 0
(-3085 5110);
DISPLAY 0.680851 (-3085 5110);
FORCEPROP 2 LAST $XR1 277 
J 0
(-3522 5100);
DISPLAY 0.638298 (-3522 5100);
PAINT MONO (-3522 5100);
FORCEPROP 2 LAST $XR0 185 
J 0
(-3402 5100);
DISPLAY 0.638298 (-3402 5100);
PAINT MONO (-3402 5100);
FORCEPROP 2 LAST CDS_LIB standard
J 2
(-3150 5100);
DISPLAY INVISIBLE (-3150 5100);
FORCEPROP 1 LAST OFFPAGE TRUE
J 0
(-2825 4975);
DISPLAY 1.170213 (-2825 4975);
PAINT GREEN (-2825 4975);
DISPLAY INVISIBLE (-2825 4975);
FORCEPROP 1 LAST COMMENT_BODY TRUE
J 0
(-3025 5000);
DISPLAY 1.170213 (-3025 5000);
PAINT GREEN (-3025 5000);
DISPLAY INVISIBLE (-3025 5000);
FORCEPROP 2 LAST PATH I88
J 0
(-3100 5175);
DISPLAY 0.680851 (-3100 5175);
DISPLAY INVISIBLE (-3100 5175);
FORCEADD OFFPAGE..3
R 2
(-3150 5050);
FORCEPROP 2 LAST $XR1 277 
J 0
(-3550 5050);
DISPLAY 0.638298 (-3550 5050);
PAINT MONO (-3550 5050);
FORCEPROP 2 LAST $XR0 185 
J 0
(-3430 5050);
DISPLAY 0.638298 (-3430 5050);
PAINT MONO (-3430 5050);
FORCEPROP 2 LAST CDS_LIB standard
J 0
(-3150 5050);
DISPLAY INVISIBLE (-3150 5050);
FORCEPROP 1 LAST OFFPAGE TRUE
J 2
(-3475 4925);
DISPLAY 0.872340 (-3475 4925);
PAINT GREEN (-3475 4925);
DISPLAY INVISIBLE (-3475 4925);
FORCEPROP 1 LAST COMMENT_BODY TRUE
J 2
(-3100 4950);
DISPLAY 0.872340 (-3100 4950);
PAINT GREEN (-3100 4950);
DISPLAY INVISIBLE (-3100 4950);
FORCEPROP 2 LAST PATH I89
J 0
(-3100 5125);
DISPLAY 0.680851 (-3100 5125);
DISPLAY INVISIBLE (-3100 5125);
FORCEADD OFFPAGE..3
R 2
(-3150 4950);
FORCEPROP 2 LAST $XR0 185 
J 0
(-3430 4950);
DISPLAY 0.638298 (-3430 4950);
PAINT MONO (-3430 4950);
FORCEPROP 2 LAST CDS_LIB standard
J 2
(-3150 4950);
DISPLAY INVISIBLE (-3150 4950);
FORCEPROP 1 LAST OFFPAGE TRUE
J 2
(-3475 4825);
DISPLAY 0.872340 (-3475 4825);
PAINT GREEN (-3475 4825);
DISPLAY INVISIBLE (-3475 4825);
FORCEPROP 1 LAST COMMENT_BODY TRUE
J 2
(-3100 4850);
DISPLAY 0.872340 (-3100 4850);
PAINT GREEN (-3100 4850);
DISPLAY INVISIBLE (-3100 4850);
FORCEPROP 2 LAST PATH I90
J 0
(-3100 5025);
DISPLAY 0.680851 (-3100 5025);
DISPLAY INVISIBLE (-3100 5025);
FORCEADD OFFPAGE..1
(-3150 5000);
FORCEPROP 2 LAST $XR0 185 
J 0
(-3432 5000);
DISPLAY 0.638298 (-3432 5000);
PAINT MONO (-3432 5000);
FORCEPROP 2 LAST CDS_LIB standard
J 0
(-3150 5000);
DISPLAY INVISIBLE (-3150 5000);
FORCEPROP 1 LAST OFFPAGE TRUE
J 0
(-2825 4875);
DISPLAY 1.170213 (-2825 4875);
PAINT GREEN (-2825 4875);
DISPLAY INVISIBLE (-2825 4875);
FORCEPROP 1 LAST COMMENT_BODY TRUE
J 0
(-3025 4900);
DISPLAY 1.170213 (-3025 4900);
PAINT GREEN (-3025 4900);
DISPLAY INVISIBLE (-3025 4900);
FORCEPROP 2 LAST PATH I91
J 0
(-3100 5075);
DISPLAY 0.680851 (-3100 5075);
DISPLAY INVISIBLE (-3100 5075);
FORCEADD OFFPAGE..2
(-625 3675);
FORCEPROP 2 LAST $XR1 290 
J 0
(-316 3675);
DISPLAY 0.638298 (-316 3675);
PAINT MONO (-316 3675);
FORCEPROP 2 LAST $XR0 185 
J 0
(-436 3675);
DISPLAY 0.638298 (-436 3675);
PAINT MONO (-436 3675);
FORCEPROP 2 LAST CDS_LIB standard
J 2
(-625 3675);
DISPLAY INVISIBLE (-625 3675);
FORCEPROP 1 LAST OFFPAGE TRUE
J 0
(-300 3550);
DISPLAY 0.872340 (-300 3550);
PAINT GREEN (-300 3550);
DISPLAY INVISIBLE (-300 3550);
FORCEPROP 1 LAST COMMENT_BODY TRUE
J 0
(-670 3580);
DISPLAY 0.872340 (-670 3580);
PAINT GREEN (-670 3580);
DISPLAY INVISIBLE (-670 3580);
FORCEPROP 2 LAST PATH I92
J 0
(-450 3750);
DISPLAY 0.680851 (-450 3750);
DISPLAY INVISIBLE (-450 3750);
FORCEADD OFFPAGE..3
(-625 3625);
FORCEPROP 2 LAST $XR1 290 
J 0
(-291 3625);
DISPLAY 0.638298 (-291 3625);
PAINT MONO (-291 3625);
FORCEPROP 2 LAST $XR0 185 
J 0
(-411 3625);
DISPLAY 0.638298 (-411 3625);
PAINT MONO (-411 3625);
FORCEPROP 2 LAST CDS_LIB standard
J 2
(-625 3625);
DISPLAY INVISIBLE (-625 3625);
FORCEPROP 1 LAST OFFPAGE TRUE
J 0
(-300 3500);
DISPLAY 0.872340 (-300 3500);
PAINT GREEN (-300 3500);
DISPLAY INVISIBLE (-300 3500);
FORCEPROP 1 LAST COMMENT_BODY TRUE
J 0
(-675 3525);
DISPLAY 0.872340 (-675 3525);
PAINT GREEN (-675 3525);
DISPLAY INVISIBLE (-675 3525);
FORCEPROP 2 LAST PATH I93
J 0
(-425 3700);
DISPLAY 0.680851 (-425 3700);
DISPLAY INVISIBLE (-425 3700);
FORCEADD OFFPAGE..2
(-675 2200);
FORCEPROP 2 LAST $XR1 312 
J 0
(-366 2200);
DISPLAY 0.638298 (-366 2200);
PAINT MONO (-366 2200);
FORCEPROP 2 LAST $XR0 185 
J 0
(-486 2200);
DISPLAY 0.638298 (-486 2200);
PAINT MONO (-486 2200);
FORCEPROP 2 LAST CDS_LIB standard
J 2
(-675 2200);
DISPLAY INVISIBLE (-675 2200);
FORCEPROP 1 LAST OFFPAGE TRUE
J 0
(-350 2075);
DISPLAY 0.872340 (-350 2075);
PAINT GREEN (-350 2075);
DISPLAY INVISIBLE (-350 2075);
FORCEPROP 1 LAST COMMENT_BODY TRUE
J 0
(-720 2105);
DISPLAY 0.872340 (-720 2105);
PAINT GREEN (-720 2105);
DISPLAY INVISIBLE (-720 2105);
FORCEPROP 2 LAST PATH I94
J 0
(-500 2275);
DISPLAY 0.680851 (-500 2275);
DISPLAY INVISIBLE (-500 2275);
FORCEADD OFFPAGE..3
(-675 2150);
FORCEPROP 2 LAST $XR1 312 
J 0
(-341 2150);
DISPLAY 0.638298 (-341 2150);
PAINT MONO (-341 2150);
FORCEPROP 2 LAST $XR0 185 
J 0
(-461 2150);
DISPLAY 0.638298 (-461 2150);
PAINT MONO (-461 2150);
FORCEPROP 2 LAST CDS_LIB standard
J 2
(-675 2150);
DISPLAY INVISIBLE (-675 2150);
FORCEPROP 1 LAST OFFPAGE TRUE
J 0
(-350 2025);
DISPLAY 0.872340 (-350 2025);
PAINT GREEN (-350 2025);
DISPLAY INVISIBLE (-350 2025);
FORCEPROP 1 LAST COMMENT_BODY TRUE
J 0
(-725 2050);
DISPLAY 0.872340 (-725 2050);
PAINT GREEN (-725 2050);
DISPLAY INVISIBLE (-725 2050);
FORCEPROP 2 LAST PATH I95
J 0
(-475 2225);
DISPLAY 0.680851 (-475 2225);
DISPLAY INVISIBLE (-475 2225);
FORCEADD UNIVERSAL_GND..1
(-1150 3825);
FORCEPROP 3 LASTPIN (-1150 3875) SIG_NAME GND\g
J 0
(-1140 3885);
DISPLAY 0.659574 (-1140 3885);
PAINT MONO (-1140 3885);
DISPLAY INVISIBLE (-1140 3885);
FORCEPROP 2 LAST CDS_LIB pure_quanta_power
J 0
(-1150 3825);
DISPLAY INVISIBLE (-1150 3825);
FORCEPROP 1 LAST HDL_POWER GND
J 1
(-1125 3750);
DISPLAY 0.872340 (-1125 3750);
PAINT GREEN (-1125 3750);
DISPLAY INVISIBLE (-1125 3750);
FORCEPROP 1 LAST PATH I96
J 0
(-1075 3825);
DISPLAY 0.872340 (-1075 3825);
PAINT AQUA (-1075 3825);
DISPLAY INVISIBLE (-1075 3825);
FORCEADD UNIVERSAL_GND..1
(-1450 3275);
FORCEPROP 3 LASTPIN (-1450 3325) SIG_NAME GND\g
J 0
(-1440 3335);
DISPLAY 0.659574 (-1440 3335);
PAINT MONO (-1440 3335);
DISPLAY INVISIBLE (-1440 3335);
FORCEPROP 2 LAST CDS_LIB pure_quanta_power
J 0
(-1450 3275);
DISPLAY INVISIBLE (-1450 3275);
FORCEPROP 1 LAST HDL_POWER GND
J 1
(-1425 3200);
DISPLAY 0.872340 (-1425 3200);
PAINT GREEN (-1425 3200);
DISPLAY INVISIBLE (-1425 3200);
FORCEPROP 1 LAST PATH I97
J 0
(-1375 3275);
DISPLAY 0.872340 (-1375 3275);
PAINT AQUA (-1375 3275);
DISPLAY INVISIBLE (-1375 3275);
FORCEADD UNIVERSAL_GND..1
(-1200 2350);
FORCEPROP 3 LASTPIN (-1200 2400) SIG_NAME GND\g
J 0
(-1190 2410);
DISPLAY 0.659574 (-1190 2410);
PAINT MONO (-1190 2410);
DISPLAY INVISIBLE (-1190 2410);
FORCEPROP 2 LAST CDS_LIB pure_quanta_power
J 0
(-1200 2350);
DISPLAY INVISIBLE (-1200 2350);
FORCEPROP 1 LAST HDL_POWER GND
J 1
(-1175 2275);
DISPLAY 0.872340 (-1175 2275);
PAINT GREEN (-1175 2275);
DISPLAY INVISIBLE (-1175 2275);
FORCEPROP 1 LAST PATH I98
J 0
(-1125 2350);
DISPLAY 0.872340 (-1125 2350);
PAINT AQUA (-1125 2350);
DISPLAY INVISIBLE (-1125 2350);
FORCEADD Q_CAP..1
(-1200 2550);
FORCEPROP 1 LAST LOCATION C1070
J 0
(-1150 2650);
DISPLAY 0.808511 (-1150 2650);
FORCEPROP 0 LAST $SEC 1
J 0
(-1150 2700);
DISPLAY 0.680851 (-1150 2700);
PAINT MONO (-1150 2700);
DISPLAY INVISIBLE (-1150 2700);
FORCEPROP 0 LAST CDS_SEC 1
J 0
(-1150 2700);
DISPLAY 0.680851 (-1150 2700);
DISPLAY INVISIBLE (-1150 2700);
FORCEPROP 1 LASTPIN (-1200 2650) $PN 1
J 0
(-1190 2630);
DISPLAY 0.787234 (-1190 2630);
PAINT MONO (-1190 2630);
FORCEPROP 1 LASTPIN (-1200 2450) $PN 2
J 0
(-1190 2430);
DISPLAY 0.787234 (-1190 2430);
PAINT MONO (-1190 2430);
FORCEPROP 1 LAST MATERIAL X7S
J 0
(-1150 2450);
DISPLAY 0.638298 (-1150 2450);
FORCEPROP 1 LAST TOLERANCE 10%
J 0
(-1150 2500);
DISPLAY 0.638298 (-1150 2500);
FORCEPROP 1 LAST PACK_TYPE C0201
J 0
(-1150 2350);
DISPLAY 0.638298 (-1150 2350);
FORCEPROP 1 LAST VOLTAGE 10V
J 0
(-1150 2550);
DISPLAY 0.638298 (-1150 2550);
FORCEPROP 1 LAST VALUE 0.1UF
J 0
(-1150 2600);
DISPLAY 0.638298 (-1150 2600);
FORCEPROP 2 LAST CDS_LIB pure_quanta
J 0
(-1200 2550);
DISPLAY INVISIBLE (-1200 2550);
FORCEPROP 1 LAST PATH I99
J 0
(-1150 2700);
DISPLAY 0.978723 (-1150 2700);
PAINT WHITE (-1150 2700);
DISPLAY INVISIBLE (-1150 2700);
FORCEPROP 1 LAST PART_NUMBER CH4102K6E00
J 0
(-1150 2400);
DISPLAY 0.638298 (-1150 2400);
DISPLAY INVISIBLE (-1150 2400);
FORCEADD QUANTA_TITLE_BLOCK_C..1
(0 0);
FORCEPROP 0 LAST CDS_CON_LAST_MODIFIED Thu Sep 14 16:13:11 2023
J 0
(-1885 15);
DISPLAY INVISIBLE (-1885 15);
FORCEPROP 1 LAST CUSTOM_TXT_CDS <CON_LAST_MODIFIED>
J 0
(-1885 15);
DISPLAY 0.978723 (-1885 15);
FORCEPROP 2 LAST CUSTOM_TXT_CDS <XR_PAGE_TITLE>
J 0
(-7890 5250);
DISPLAY 0.638298 (-7890 5250);
PAINT PINK (-7890 5250);
DISPLAY INVISIBLE (-7890 5250);
FORCEPROP 1 LAST CUSTOM_TXT_CDS <NAME_2>
J 0
(-3175 50);
FORCEPROP 1 LAST CUSTOM_TXT_CDS <NAME_1>
J 0
(-3175 175);
FORCEPROP 1 LAST CUSTOM_TXT_CDS <Q_NUMBER>
J 0
(-1403 103);
DISPLAY 1.212766 (-1403 103);
FORCEPROP 1 LAST CUSTOM_TXT_CDS <Q_PROJ>
J 0
(-2382 102);
DISPLAY 1.212766 (-2382 102);
FORCEPROP 1 LAST CUSTOM_TXT_CDS <Q_REV>
J 0
(-184 103);
DISPLAY 1.212766 (-184 103);
FORCEPROP 1 LAST CUSTOM_TXT_CDS <CON_PAGE_NUM> OF <CON_TOTAL_PAGES>
J 0
(-446 18);
DISPLAY 0.978723 (-446 18);
FORCEPROP 1 LAST Q_TITLE SMBUS-RETIMER EEPROM MUX
J 0
(-9366 26);
DISPLAY 2.446809 (-9366 26);
PAINT GREEN (-9366 26);
FORCEPROP 2 LAST CDS_LIB pure_quanta
J 0
(0 0);
DISPLAY INVISIBLE (0 0);
FORCEPROP 1 LAST CDS_LMAN_SYM_OUTLINE -9475,6775,100,-125
J 0
(0 0);
DISPLAY 0.468085 (0 0);
PAINT GREEN (0 0);
DISPLAY INVISIBLE (0 0);
FORCEPROP 2 LAST PAGE_BORDER TRUE
J 0
(-7890 5250);
DISPLAY 0.638298 (-7890 5250);
PAINT PINK (-7890 5250);
DISPLAY INVISIBLE (-7890 5250);
FORCEPROP 2 LAST CDS_XR_PAGE_TITLE CR-186 : @T6G_MB_LIB.T6G(SCH_1):PAGE186
J 0
(-7890 5250);
DISPLAY 0.638298 (-7890 5250);
PAINT PINK (-7890 5250);
DISPLAY INVISIBLE (-7890 5250);
FORCEPROP 1 LAST Q_DEPT BU9
J 1
(-3763 49);
DISPLAY 1.957447 (-3763 49);
PAINT GREEN (-3763 49);
DISPLAY INVISIBLE (-3763 49);
FORCEPROP 1 LAST COMMENT_BODY TRUE
J 0
(12 -13);
DISPLAY 0.978723 (12 -13);
PAINT GREEN (12 -13);
DISPLAY INVISIBLE (12 -13);
WIRE 16 -1 (-1175 1025)(-1175 975);
WIRE 16 -1 (-3125 5250)(-4175 5250);
WIRE 16 -1 (-3200 3725)(-4250 3725);
WIRE 16 -1 (-3250 2250)(-4300 2250);
WIRE 16 -1 (-3225 825)(-4275 825);
WIRE 16 -1 (-5450 5975)(-5450 5925);
WIRE 16 -1 (-7500 5775)(-8550 5775);
WIRE 16 -1 (-5525 4550)(-5525 4500);
WIRE 16 -1 (-7575 4350)(-8625 4350);
WIRE 16 -1 (-5575 3075)(-5575 3025);
WIRE 16 -1 (-7625 2875)(-8675 2875);
WIRE 16 -1 (-5525 1475)(-5525 1425);
WIRE 16 -1 (-7575 1275)(-8625 1275);
WIRE 16 -1 (-1075 5450)(-1075 5400);
WIRE 16 -1 (-1150 3925)(-1150 3875);
WIRE 16 -1 (-1200 2450)(-1200 2400);
WIRE 16 -1 (-7475 5475)(-6450 5475);
FORCEPROP 2 LAST SIG_NAME SMB_RT_CPU1_P0_ROM_MUX_2D_SDA
J 0
(-7460 5485);
DISPLAY 0.680851 (-7460 5485);
WIRE 16 -1 (-5450 6250)(-5600 6250);
WIRE 16 -1 (-5450 6175)(-5450 6250);
WIRE 16 -1 (-5600 6300)(-5600 6250);
WIRE 16 -1 (-5600 6250)(-5600 5775);
WIRE 16 -1 (-5600 5775)(-5850 5775);
WIRE 16 -1 (-7475 5525)(-6450 5525);
FORCEPROP 2 LAST SIG_NAME SMB_RT_CPU1_P0_ROM_MUX_2D_SCL
J 0
(-7460 5535);
DISPLAY 0.680851 (-7460 5535);
WIRE 16 -1 (-7475 5575)(-6450 5575);
FORCEPROP 2 LAST SIG_NAME SMB_RT_CPU1_P0_ROM_MUX_1D_SDA
J 0
(-7460 5585);
DISPLAY 0.680851 (-7460 5585);
WIRE 16 -1 (-7475 5625)(-6450 5625);
WIRE 16 -1 (-7500 5725)(-8650 5725);
FORCEPROP 2 LAST SIG_NAME RST_SMB_RT_ROM_R1_N
J 0
(-8535 5735);
DISPLAY 0.680851 (-8535 5735);
WIRE 16 -1 (-3200 3675)(-4350 3675);
FORCEPROP 2 LAST SIG_NAME RST_SMB_RT_ROM_R1_N
J 0
(-4235 3685);
DISPLAY 0.680851 (-4235 3685);
WIRE 16 -1 (-7575 4300)(-8725 4300);
FORCEPROP 2 LAST SIG_NAME RST_SMB_RT_ROM_R1_N
J 0
(-8610 4310);
DISPLAY 0.680851 (-8610 4310);
WIRE 16 -1 (-7625 2825)(-8775 2825);
FORCEPROP 2 LAST SIG_NAME RST_SMB_RT_ROM_R1_N
J 0
(-8660 2835);
DISPLAY 0.680851 (-8660 2835);
WIRE 16 -1 (-7575 1225)(-8725 1225);
FORCEPROP 2 LAST SIG_NAME RST_SMB_RT_ROM_R1_N
J 0
(-8610 1235);
DISPLAY 0.680851 (-8610 1235);
WIRE 16 -1 (-3250 2200)(-4400 2200);
FORCEPROP 2 LAST SIG_NAME RST_SMB_RT_ROM_R1_N
J 0
(-4285 2210);
DISPLAY 0.680851 (-4285 2210);
WIRE 16 -1 (-3225 775)(-4375 775);
FORCEPROP 2 LAST SIG_NAME RST_SMB_RT_ROM_R1_N
J 0
(-4260 785);
DISPLAY 0.680851 (-4260 785);
WIRE 16 -1 (-3125 5200)(-4275 5200);
FORCEPROP 2 LAST SIG_NAME RST_SMB_RT_ROM_R1_N
J 0
(-4160 5210);
DISPLAY 0.680851 (-4160 5210);
WIRE 16 -1 (-7550 1025)(-6525 1025);
FORCEPROP 2 LAST SIG_NAME SMB_RT_CPU1_P2_ROM_MUX_2D_SCL
J 0
(-7535 1035);
DISPLAY 0.680851 (-7535 1035);
WIRE 16 -1 (-4975 5725)(-5850 5725);
FORCEPROP 2 LAST SIG_NAME SMB_RT_CPU1_P0_ROM_R_SCL
J 0
(-5810 5735);
DISPLAY 0.680851 (-5810 5735);
WIRE 16 -1 (-4975 5675)(-5850 5675);
FORCEPROP 2 LAST SIG_NAME SMB_RT_CPU1_P0_ROM_R_SDA
J 0
(-5810 5685);
DISPLAY 0.680851 (-5810 5685);
WIRE 16 -1 (-7300 5725)(-6450 5725);
FORCEPROP 2 LAST SIG_NAME FM_SMB_RT_ROM_MUX1_SEL
J 0
(-7060 5735);
DISPLAY 0.553191 (-7060 5735);
FORCEPROP 2 LASTPROP $XRERR UNIQUE?
J 0
(-7300 5735);
DISPLAY 0.638298 (-7300 5735);
PAINT MONO (-7300 5735);
DISPLAY INVISIBLE (-7300 5735);
WIRE 16 -1 (-7300 5775)(-6450 5775);
FORCEPROP 2 LAST SIG_NAME RT_ROM_MUX1_OE_N
J 0
(-7060 5785);
DISPLAY 0.680851 (-7060 5785);
FORCEPROP 2 LASTPROP $XRERR UNIQUE?
J 0
(-7300 5785);
DISPLAY 0.638298 (-7300 5785);
PAINT MONO (-7300 5785);
DISPLAY INVISIBLE (-7300 5785);
WIRE 16 -1 (-5050 4300)(-5925 4300);
FORCEPROP 2 LAST SIG_NAME SMB_RT_CPU1_P1_ROM_R_SCL
J 0
(-5885 4310);
DISPLAY 0.680851 (-5885 4310);
WIRE 16 -1 (-5050 4250)(-5925 4250);
FORCEPROP 2 LAST SIG_NAME SMB_RT_CPU1_P1_ROM_R_SDA
J 0
(-5885 4260);
DISPLAY 0.680851 (-5885 4260);
WIRE 16 -1 (-7550 4100)(-6525 4100);
FORCEPROP 2 LAST SIG_NAME SMB_RT_CPU1_P1_ROM_MUX_2D_SCL
J 0
(-7535 4110);
DISPLAY 0.680851 (-7535 4110);
WIRE 16 -1 (-7550 4050)(-6525 4050);
FORCEPROP 2 LAST SIG_NAME SMB_RT_CPU1_P1_ROM_MUX_2D_SDA
J 0
(-7535 4060);
DISPLAY 0.680851 (-7535 4060);
WIRE 16 -1 (-7550 4150)(-6525 4150);
FORCEPROP 2 LAST SIG_NAME SMB_RT_CPU1_P1_ROM_MUX_1D_SDA
J 0
(-7535 4160);
DISPLAY 0.680851 (-7535 4160);
WIRE 16 -1 (-5100 2825)(-5975 2825);
FORCEPROP 2 LAST SIG_NAME SMB_RT_CPU1_P3_ROM_R_SCL
J 0
(-5935 2835);
DISPLAY 0.680851 (-5935 2835);
WIRE 16 -1 (-7425 2825)(-6575 2825);
FORCEPROP 2 LAST SIG_NAME FM_SMB_RT_ROM_MUX3_SEL
J 0
(-7185 2835);
DISPLAY 0.553191 (-7185 2835);
FORCEPROP 2 LASTPROP $XRERR UNIQUE?
J 0
(-7425 2835);
DISPLAY 0.638298 (-7425 2835);
PAINT MONO (-7425 2835);
DISPLAY INVISIBLE (-7425 2835);
WIRE 16 -1 (-7425 2875)(-6575 2875);
FORCEPROP 2 LAST SIG_NAME RT_ROM_MUX3_OE_N
J 0
(-7185 2885);
DISPLAY 0.680851 (-7185 2885);
FORCEPROP 2 LASTPROP $XRERR UNIQUE?
J 0
(-7425 2885);
DISPLAY 0.638298 (-7425 2885);
PAINT MONO (-7425 2885);
DISPLAY INVISIBLE (-7425 2885);
WIRE 16 -1 (-7600 2725)(-6575 2725);
WIRE 16 -1 (-7600 2675)(-6575 2675);
FORCEPROP 2 LAST SIG_NAME SMB_RT_CPU1_P3_ROM_MUX_1D_SDA
J 0
(-7585 2685);
DISPLAY 0.680851 (-7585 2685);
WIRE 16 -1 (-7600 2625)(-6575 2625);
FORCEPROP 2 LAST SIG_NAME SMB_RT_CPU1_P3_ROM_MUX_2D_SCL
J 0
(-7585 2635);
DISPLAY 0.680851 (-7585 2635);
WIRE 16 -1 (-7600 2575)(-6575 2575);
FORCEPROP 2 LAST SIG_NAME SMB_RT_CPU1_P3_ROM_MUX_2D_SDA
J 0
(-7585 2585);
DISPLAY 0.680851 (-7585 2585);
WIRE 16 -1 (-7375 1275)(-6525 1275);
FORCEPROP 2 LAST SIG_NAME RT_ROM_MUX4_OE_N
J 0
(-7135 1285);
DISPLAY 0.680851 (-7135 1285);
FORCEPROP 2 LASTPROP $XRERR UNIQUE?
J 0
(-7375 1285);
DISPLAY 0.638298 (-7375 1285);
PAINT MONO (-7375 1285);
DISPLAY INVISIBLE (-7375 1285);
WIRE 16 -1 (-7375 1225)(-6525 1225);
FORCEPROP 2 LAST SIG_NAME FM_SMB_RT_ROM_MUX4_SEL
J 0
(-7135 1235);
DISPLAY 0.553191 (-7135 1235);
FORCEPROP 2 LASTPROP $XRERR UNIQUE?
J 0
(-7375 1235);
DISPLAY 0.638298 (-7375 1235);
PAINT MONO (-7375 1235);
DISPLAY INVISIBLE (-7375 1235);
WIRE 16 -1 (-7550 1125)(-6525 1125);
WIRE 16 -1 (-7550 1075)(-6525 1075);
FORCEPROP 2 LAST SIG_NAME SMB_RT_CPU1_P2_ROM_MUX_1D_SDA
J 0
(-7535 1085);
DISPLAY 0.680851 (-7535 1085);
WIRE 16 -1 (-7550 975)(-6525 975);
FORCEPROP 2 LAST SIG_NAME SMB_RT_CPU1_P2_ROM_MUX_2D_SDA
J 0
(-7535 985);
DISPLAY 0.680851 (-7535 985);
WIRE 16 -1 (-5050 1175)(-5925 1175);
FORCEPROP 2 LAST SIG_NAME SMB_RT_CPU1_P2_ROM_R_SDA
J 0
(-5885 1185);
DISPLAY 0.680851 (-5885 1185);
WIRE 16 -1 (-5050 1225)(-5925 1225);
FORCEPROP 2 LAST SIG_NAME SMB_RT_CPU1_P2_ROM_R_SCL
J 0
(-5885 1235);
DISPLAY 0.680851 (-5885 1235);
WIRE 16 -1 (-7375 4350)(-6525 4350);
FORCEPROP 2 LAST SIG_NAME RT_ROM_MUX2_OE_N
J 0
(-7135 4360);
DISPLAY 0.680851 (-7135 4360);
FORCEPROP 2 LASTPROP $XRERR UNIQUE?
J 0
(-7375 4360);
DISPLAY 0.638298 (-7375 4360);
PAINT MONO (-7375 4360);
DISPLAY INVISIBLE (-7375 4360);
WIRE 16 -1 (-7375 4300)(-6525 4300);
FORCEPROP 2 LAST SIG_NAME FM_SMB_RT_ROM_MUX2_SEL
J 0
(-7135 4310);
DISPLAY 0.553191 (-7135 4310);
FORCEPROP 2 LASTPROP $XRERR UNIQUE?
J 0
(-7375 4310);
DISPLAY 0.638298 (-7375 4310);
PAINT MONO (-7375 4310);
DISPLAY INVISIBLE (-7375 4310);
WIRE 16 -1 (-7550 4200)(-6525 4200);
WIRE 16 -1 (-5100 2775)(-5975 2775);
FORCEPROP 2 LAST SIG_NAME SMB_RT_CPU1_P3_ROM_R_SDA
J 0
(-5935 2785);
DISPLAY 0.680851 (-5935 2785);
WIRE 16 -1 (-3100 5100)(-2075 5100);
WIRE 16 -1 (-2925 5250)(-2075 5250);
FORCEPROP 2 LAST SIG_NAME RT_ROM_MUX5_OE_N
J 0
(-2685 5260);
DISPLAY 0.680851 (-2685 5260);
FORCEPROP 2 LASTPROP $XRERR UNIQUE?
J 0
(-2925 5260);
DISPLAY 0.638298 (-2925 5260);
PAINT MONO (-2925 5260);
DISPLAY INVISIBLE (-2925 5260);
WIRE 16 -1 (-2925 5200)(-2075 5200);
FORCEPROP 2 LAST SIG_NAME FM_SMB_RT_ROM_MUX5_SEL
J 0
(-2685 5210);
DISPLAY 0.553191 (-2685 5210);
FORCEPROP 2 LASTPROP $XRERR UNIQUE?
J 0
(-2925 5210);
DISPLAY 0.638298 (-2925 5210);
PAINT MONO (-2925 5210);
DISPLAY INVISIBLE (-2925 5210);
WIRE 16 -1 (-3100 5050)(-2075 5050);
FORCEPROP 2 LAST SIG_NAME SMB_RT_CPU0_P0_ROM_MUX_1D_SDA
J 0
(-3085 5060);
DISPLAY 0.680851 (-3085 5060);
WIRE 16 -1 (-3100 5000)(-2075 5000);
FORCEPROP 2 LAST SIG_NAME SMB_RT_CPU0_P0_ROM_MUX_2D_SCL
J 0
(-3085 5010);
DISPLAY 0.680851 (-3085 5010);
WIRE 16 -1 (-3100 4950)(-2075 4950);
FORCEPROP 2 LAST SIG_NAME SMB_RT_CPU0_P0_ROM_MUX_2D_SDA
J 0
(-3085 4960);
DISPLAY 0.680851 (-3085 4960);
WIRE 16 -1 (-600 5200)(-1475 5200);
FORCEPROP 2 LAST SIG_NAME SMB_RT_CPU0_P0_ROM_R_SCL
J 0
(-1435 5210);
DISPLAY 0.680851 (-1435 5210);
WIRE 16 -1 (-600 5150)(-1475 5150);
FORCEPROP 2 LAST SIG_NAME SMB_RT_CPU0_P0_ROM_R_SDA
J 0
(-1435 5160);
DISPLAY 0.680851 (-1435 5160);
WIRE 16 -1 (-1375 4950)(-1475 4950);
WIRE 16 -1 (-1375 4850)(-1375 4950);
WIRE 16 -1 (-1150 4200)(-1300 4200);
WIRE 16 -1 (-1150 4125)(-1150 4200);
WIRE 16 -1 (-1300 4250)(-1300 4200);
WIRE 16 -1 (-1300 4200)(-1300 3725);
WIRE 16 -1 (-1300 3725)(-1550 3725);
WIRE 16 -1 (-1075 5725)(-1225 5725);
WIRE 16 -1 (-1075 5650)(-1075 5725);
WIRE 16 -1 (-1225 5775)(-1225 5725);
WIRE 16 -1 (-1225 5725)(-1225 5250);
WIRE 16 -1 (-1225 5250)(-1475 5250);
WIRE 16 -1 (-5825 875)(-5825 975);
WIRE 16 -1 (-5825 975)(-5925 975);
WIRE 16 -1 (-5525 1750)(-5675 1750);
WIRE 16 -1 (-5525 1675)(-5525 1750);
WIRE 16 -1 (-5675 1800)(-5675 1750);
WIRE 16 -1 (-5675 1750)(-5675 1275);
WIRE 16 -1 (-5675 1275)(-5925 1275);
WIRE 16 -1 (-5875 2575)(-5975 2575);
WIRE 16 -1 (-5875 2475)(-5875 2575);
WIRE 16 -1 (-5575 3350)(-5725 3350);
WIRE 16 -1 (-5575 3275)(-5575 3350);
WIRE 16 -1 (-5725 3400)(-5725 3350);
WIRE 16 -1 (-5725 3350)(-5725 2875);
WIRE 16 -1 (-5725 2875)(-5975 2875);
WIRE 16 -1 (-5825 3950)(-5825 4050);
WIRE 16 -1 (-5825 4050)(-5925 4050);
WIRE 16 -1 (-5525 4825)(-5675 4825);
WIRE 16 -1 (-5525 4750)(-5525 4825);
WIRE 16 -1 (-5675 4875)(-5675 4825);
WIRE 16 -1 (-5675 4825)(-5675 4350);
WIRE 16 -1 (-5675 4350)(-5925 4350);
WIRE 16 -1 (-1200 2725)(-1350 2725);
WIRE 16 -1 (-1200 2650)(-1200 2725);
WIRE 16 -1 (-1350 2775)(-1350 2725);
WIRE 16 -1 (-1350 2725)(-1350 2250);
WIRE 16 -1 (-1350 2250)(-1600 2250);
WIRE 16 -1 (-5750 5475)(-5850 5475);
WIRE 16 -1 (-5750 5375)(-5750 5475);
WIRE 16 -1 (-3000 3725)(-2150 3725);
FORCEPROP 2 LAST SIG_NAME RT_ROM_MUX6_OE_N
J 0
(-2760 3735);
DISPLAY 0.680851 (-2760 3735);
FORCEPROP 2 LASTPROP $XRERR UNIQUE?
J 0
(-3000 3735);
DISPLAY 0.638298 (-3000 3735);
PAINT MONO (-3000 3735);
DISPLAY INVISIBLE (-3000 3735);
WIRE 16 -1 (-3000 3675)(-2150 3675);
FORCEPROP 2 LAST SIG_NAME FM_SMB_RT_ROM_MUX6_SEL
J 0
(-2760 3685);
DISPLAY 0.553191 (-2760 3685);
FORCEPROP 2 LASTPROP $XRERR UNIQUE?
J 0
(-3000 3685);
DISPLAY 0.638298 (-3000 3685);
PAINT MONO (-3000 3685);
DISPLAY INVISIBLE (-3000 3685);
WIRE 16 -1 (-3175 3525)(-2150 3525);
FORCEPROP 2 LAST SIG_NAME SMB_RT_CPU0_P1_ROM_MUX_1D_SDA
J 0
(-3160 3535);
DISPLAY 0.680851 (-3160 3535);
WIRE 16 -1 (-3175 3575)(-2150 3575);
WIRE 16 -1 (-1450 3325)(-1450 3425);
WIRE 16 -1 (-1450 3425)(-1550 3425);
WIRE 16 -1 (-675 3675)(-1550 3675);
FORCEPROP 2 LAST SIG_NAME SMB_RT_CPU0_P1_ROM_R_SCL
J 0
(-1510 3685);
DISPLAY 0.680851 (-1510 3685);
WIRE 16 -1 (-3175 3425)(-2150 3425);
FORCEPROP 2 LAST SIG_NAME SMB_RT_CPU0_P1_ROM_MUX_2D_SDA
J 0
(-3160 3435);
DISPLAY 0.680851 (-3160 3435);
WIRE 16 -1 (-3175 3475)(-2150 3475);
FORCEPROP 2 LAST SIG_NAME SMB_RT_CPU0_P1_ROM_MUX_2D_SCL
J 0
(-3160 3485);
DISPLAY 0.680851 (-3160 3485);
WIRE 16 -1 (-675 3625)(-1550 3625);
FORCEPROP 2 LAST SIG_NAME SMB_RT_CPU0_P1_ROM_R_SDA
J 0
(-1510 3635);
DISPLAY 0.680851 (-1510 3635);
WIRE 16 -1 (-3050 2250)(-2200 2250);
FORCEPROP 2 LAST SIG_NAME RT_ROM_MUX7_OE_N
J 0
(-2810 2260);
DISPLAY 0.680851 (-2810 2260);
FORCEPROP 2 LASTPROP $XRERR UNIQUE?
J 0
(-3050 2260);
DISPLAY 0.638298 (-3050 2260);
PAINT MONO (-3050 2260);
DISPLAY INVISIBLE (-3050 2260);
WIRE 16 -1 (-3050 2200)(-2200 2200);
FORCEPROP 2 LAST SIG_NAME FM_SMB_RT_ROM_MUX7_SEL
J 0
(-2810 2210);
DISPLAY 0.553191 (-2810 2210);
FORCEPROP 2 LASTPROP $XRERR UNIQUE?
J 0
(-3050 2210);
DISPLAY 0.638298 (-3050 2210);
PAINT MONO (-3050 2210);
DISPLAY INVISIBLE (-3050 2210);
WIRE 16 -1 (-3225 2050)(-2200 2050);
FORCEPROP 2 LAST SIG_NAME SMB_RT_CPU0_P3_ROM_MUX_1D_SDA
J 0
(-3210 2060);
DISPLAY 0.680851 (-3210 2060);
WIRE 16 -1 (-3225 2000)(-2200 2000);
FORCEPROP 2 LAST SIG_NAME SMB_RT_CPU0_P3_ROM_MUX_2D_SCL
J 0
(-3210 2010);
DISPLAY 0.680851 (-3210 2010);
WIRE 16 -1 (-3225 1950)(-2200 1950);
FORCEPROP 2 LAST SIG_NAME SMB_RT_CPU0_P3_ROM_MUX_2D_SDA
J 0
(-3210 1960);
DISPLAY 0.680851 (-3210 1960);
WIRE 16 -1 (-1500 1850)(-1500 1950);
WIRE 16 -1 (-1500 1950)(-1600 1950);
WIRE 16 -1 (-725 2150)(-1600 2150);
FORCEPROP 2 LAST SIG_NAME SMB_RT_CPU0_P3_ROM_R_SDA
J 0
(-1560 2160);
DISPLAY 0.680851 (-1560 2160);
WIRE 16 -1 (-725 2200)(-1600 2200);
FORCEPROP 2 LAST SIG_NAME SMB_RT_CPU0_P3_ROM_R_SCL
J 0
(-1560 2210);
DISPLAY 0.680851 (-1560 2210);
WIRE 16 -1 (-3200 625)(-2175 625);
FORCEPROP 2 LAST SIG_NAME SMB_RT_CPU0_P2_ROM_MUX_1D_SDA
J 0
(-3185 635);
DISPLAY 0.680851 (-3185 635);
WIRE 16 -1 (-3200 575)(-2175 575);
FORCEPROP 2 LAST SIG_NAME SMB_RT_CPU0_P2_ROM_MUX_2D_SCL
J 0
(-3185 585);
DISPLAY 0.680851 (-3185 585);
WIRE 16 -1 (-3200 675)(-2175 675);
WIRE 16 -1 (-3025 775)(-2175 775);
FORCEPROP 2 LAST SIG_NAME FM_SMB_RT_ROM_MUX8_SEL
J 0
(-2785 785);
DISPLAY 0.553191 (-2785 785);
FORCEPROP 2 LASTPROP $XRERR UNIQUE?
J 0
(-3025 785);
DISPLAY 0.638298 (-3025 785);
PAINT MONO (-3025 785);
DISPLAY INVISIBLE (-3025 785);
WIRE 16 -1 (-3025 825)(-2175 825);
FORCEPROP 2 LAST SIG_NAME RT_ROM_MUX8_OE_N
J 0
(-2785 835);
DISPLAY 0.680851 (-2785 835);
FORCEPROP 2 LASTPROP $XRERR UNIQUE?
J 0
(-3025 835);
DISPLAY 0.638298 (-3025 835);
PAINT MONO (-3025 835);
DISPLAY INVISIBLE (-3025 835);
WIRE 16 -1 (-1175 1300)(-1325 1300);
WIRE 16 -1 (-1175 1225)(-1175 1300);
WIRE 16 -1 (-1325 1350)(-1325 1300);
WIRE 16 -1 (-1325 1300)(-1325 825);
WIRE 16 -1 (-1325 825)(-1575 825);
WIRE 16 -1 (-700 725)(-1575 725);
FORCEPROP 2 LAST SIG_NAME SMB_RT_CPU0_P2_ROM_R_SDA
J 0
(-1535 735);
DISPLAY 0.680851 (-1535 735);
WIRE 16 -1 (-700 775)(-1575 775);
FORCEPROP 2 LAST SIG_NAME SMB_RT_CPU0_P2_ROM_R_SCL
J 0
(-1535 785);
DISPLAY 0.680851 (-1535 785);
WIRE 16 -1 (-1475 425)(-1475 525);
WIRE 16 -1 (-1475 525)(-1575 525);
WIRE 16 -1 (-3200 525)(-2175 525);
FORCEPROP 2 LAST SIG_NAME SMB_RT_CPU0_P2_ROM_MUX_2D_SDA
J 0
(-3185 535);
DISPLAY 0.680851 (-3185 535);
WIRE 16 -1 (-3225 2100)(-2200 2100);
DOT 1 (-5600 6250);
DOT 1 (-5675 4825);
DOT 1 (-5725 3350);
DOT 1 (-5675 1750);
DOT 1 (-1225 5725);
DOT 1 (-1300 4200);
DOT 1 (-1350 2725);
DOT 1 (-1325 1300);
QUIT
